FILE_TYPE = MACRO_DRAWING;
SET COLOR_WIRE YELLOW;
SET COLOR_PROP ORANGE;
SET COLOR_DOT WHITE;
SET COLOR_ARC YELLOW;
SET COLOR_BODY GREEN;
SET COLOR_NOTE PURPLE;
SET PROP_DISPLAY VALUE;
SET PAGE_NUMBER P326;
FORCEADD UNIVERSAL_GND..1
(-2575 -1525);
FORCEPROP 3 LASTPIN (-2575 -1475) SIG_NAME GND\g
J 0
(-2565 -1465);
DISPLAY 0.659574 (-2565 -1465);
PAINT MONO (-2565 -1465);
DISPLAY INVISIBLE (-2565 -1465);
FORCEPROP 2 LAST CDS_LIB logical_power
J 0
(-2575 -1525);
DISPLAY INVISIBLE (-2575 -1525);
FORCEPROP 1 LAST HDL_POWER GND
J 1
(-2550 -1600);
DISPLAY 0.872340 (-2550 -1600);
PAINT GREEN (-2550 -1600);
DISPLAY INVISIBLE (-2550 -1600);
FORCEPROP 1 LAST PATH I1
J 0
(-2500 -1525);
DISPLAY 0.872340 (-2500 -1525);
PAINT AQUA (-2500 -1525);
DISPLAY INVISIBLE (-2500 -1525);
FORCEADD Q_RES..2
(-525 275);
FORCEPROP 1 LAST PART_NUMBER CS32672FB03
J 0
(-485 150);
DISPLAY 0.723404 (-485 150);
PAINT WHITE (-485 150);
DISPLAY INVISIBLE (-485 150);
FORCEPROP 1 LAST PACK_TYPE 0402LF
J 0
(-485 100);
DISPLAY 0.723404 (-485 100);
PAINT SKYBLUE (-485 100);
FORCEPROP 1 LAST VALUE 26.7K
J 0
(-480 350);
DISPLAY 0.723404 (-480 350);
PAINT SKYBLUE (-480 350);
FORCEPROP 1 LAST TOLERANCE 1%
J 0
(-480 300);
DISPLAY 0.723404 (-480 300);
PAINT SKYBLUE (-480 300);
FORCEPROP 1 LAST WATTAGE 1/16W
J 0
(-485 250);
DISPLAY 0.723404 (-485 250);
PAINT SKYBLUE (-485 250);
FORCEPROP 1 LAST MATERIAL CHIP
J 0
(-485 200);
DISPLAY 0.723404 (-485 200);
PAINT SKYBLUE (-485 200);
FORCEPROP 1 LAST LOCATION R2219
J 0
(-480 400);
DISPLAY 0.723404 (-480 400);
PAINT AQUA (-480 400);
FORCEPROP 1 LASTPIN (-525 375) $PN 1
J 0
(-520 337);
DISPLAY 0.787234 (-520 337);
PAINT MONO (-520 337);
FORCEPROP 1 LASTPIN (-525 175) $PN 2
J 0
(-520 185);
DISPLAY 0.787234 (-520 185);
PAINT MONO (-520 185);
FORCEPROP 2 LAST CDS_LIB pure_quanta
J 0
(-525 275);
DISPLAY INVISIBLE (-525 275);
FORCEPROP 1 LAST PATH I100
J 0
(-475 450);
DISPLAY 0.978723 (-475 450);
PAINT WHITE (-475 450);
DISPLAY INVISIBLE (-475 450);
FORCEPROP 0 LAST $SEC 1
J 0
(-475 450);
DISPLAY 0.680851 (-475 450);
PAINT MONO (-475 450);
DISPLAY INVISIBLE (-475 450);
FORCEPROP 0 LAST CDS_SEC 1
J 0
(-475 450);
DISPLAY 1.021277 (-475 450);
DISPLAY INVISIBLE (-475 450);
FORCEADD Q_RES..2
(-525 -475);
FORCEPROP 1 LAST PART_NUMBER CS21002FB06
J 0
(-485 -600);
DISPLAY 0.723404 (-485 -600);
PAINT WHITE (-485 -600);
DISPLAY INVISIBLE (-485 -600);
FORCEPROP 1 LAST PACK_TYPE 0402LF
J 0
(-485 -650);
DISPLAY 0.723404 (-485 -650);
PAINT SKYBLUE (-485 -650);
FORCEPROP 1 LAST VALUE 1K
J 0
(-480 -400);
DISPLAY 0.723404 (-480 -400);
PAINT SKYBLUE (-480 -400);
FORCEPROP 1 LAST TOLERANCE 1%
J 0
(-480 -450);
DISPLAY 0.723404 (-480 -450);
PAINT SKYBLUE (-480 -450);
FORCEPROP 1 LAST MATERIAL CHIP
J 0
(-485 -550);
DISPLAY 0.723404 (-485 -550);
PAINT SKYBLUE (-485 -550);
FORCEPROP 1 LAST WATTAGE 1/16W
J 0
(-485 -500);
DISPLAY 0.723404 (-485 -500);
PAINT SKYBLUE (-485 -500);
FORCEPROP 1 LAST LOCATION R2227
J 0
(-480 -350);
DISPLAY 0.723404 (-480 -350);
PAINT AQUA (-480 -350);
FORCEPROP 1 LASTPIN (-525 -375) $PN 1
J 0
(-520 -413);
DISPLAY 0.787234 (-520 -413);
PAINT MONO (-520 -413);
FORCEPROP 1 LASTPIN (-525 -575) $PN 2
J 0
(-520 -565);
DISPLAY 0.787234 (-520 -565);
PAINT MONO (-520 -565);
FORCEPROP 1 LAST PATH I101
J 0
(-475 -300);
DISPLAY 0.978723 (-475 -300);
PAINT WHITE (-475 -300);
DISPLAY INVISIBLE (-475 -300);
FORCEPROP 2 LAST CDS_LIB pure_quanta
J 0
(-525 -475);
DISPLAY INVISIBLE (-525 -475);
FORCEPROP 0 LAST $SEC 1
J 0
(-475 -300);
DISPLAY 0.680851 (-475 -300);
PAINT MONO (-475 -300);
DISPLAY INVISIBLE (-475 -300);
FORCEPROP 0 LAST CDS_SEC 1
J 0
(-475 -300);
DISPLAY 1.021277 (-475 -300);
DISPLAY INVISIBLE (-475 -300);
FORCEADD LT6700CS61TRPBF..1
(1850 -175);
FORCEPROP 1 LAST PART_NUMBER AL006700001
J 0
(1631 109);
DISPLAY 0.723404 (1631 109);
PAINT GREEN (1631 109);
DISPLAY INVISIBLE (1631 109);
FORCEPROP 1 LAST MATERIAL IC
J 0
(1631 -18);
DISPLAY 0.723404 (1631 -18);
PAINT GREEN (1631 -18);
FORCEPROP 2 LAST VALUE LT6700CS6-1#TRPBF
J 0
(1650 300);
DISPLAY 0.808511 (1650 300);
FORCEPROP 2 LAST PART_TYPE SMLF
J 0
(1650 350);
DISPLAY 1.021277 (1650 350);
FORCEPROP 1 LAST LOCATION U206
J 0
(1631 256);
DISPLAY 0.723404 (1631 256);
PAINT GREEN (1631 256);
FORCEPROP 0 LASTPIN (2225 -275) $PN 2
J 0
(2235 -265);
DISPLAY 0.680851 (2235 -265);
PAINT MONO (2235 -265);
FORCEPROP 0 LASTPIN (1475 -125) $PN 3
J 2
(1465 -115);
DISPLAY 0.680851 (1465 -115);
PAINT MONO (1465 -115);
FORCEPROP 0 LASTPIN (1475 -225) $PN 4
J 2
(1465 -215);
DISPLAY 0.680851 (1465 -215);
PAINT MONO (1465 -215);
FORCEPROP 0 LASTPIN (2225 -125) $PN 1
J 0
(2235 -115);
DISPLAY 0.680851 (2235 -115);
PAINT MONO (2235 -115);
FORCEPROP 0 LASTPIN (2225 -225) $PN 6
J 0
(2235 -215);
DISPLAY 0.680851 (2235 -215);
PAINT MONO (2235 -215);
FORCEPROP 0 LASTPIN (1475 -75) $PN 5
J 2
(1465 -65);
DISPLAY 0.680851 (1465 -65);
PAINT MONO (1465 -65);
FORCEPROP 1 LAST CDS_LMAN_SYM_OUTLINE -225,150,225,-150
J 0
(1850 -175);
DISPLAY 0.468085 (1850 -175);
PAINT GREEN (1850 -175);
DISPLAY INVISIBLE (1850 -175);
FORCEPROP 1 LAST NEEDS_NO_SIZE TRUE
J 0
(1850 -175);
DISPLAY 0.723404 (1850 -175);
PAINT GREEN (1850 -175);
DISPLAY INVISIBLE (1850 -175);
FORCEPROP 1 LAST PATH I102
J 0
(1850 -175);
DISPLAY 0.723404 (1850 -175);
PAINT GREEN (1850 -175);
DISPLAY INVISIBLE (1850 -175);
FORCEPROP 2 LAST CDS_LIB pure_quanta
J 0
(1850 -175);
DISPLAY INVISIBLE (1850 -175);
FORCEPROP 0 LAST $SEC 1
J 0
(1650 400);
DISPLAY 0.680851 (1650 400);
PAINT MONO (1650 400);
DISPLAY INVISIBLE (1650 400);
FORCEPROP 0 LAST CDS_SEC 1
J 0
(1650 400);
DISPLAY 1.021277 (1650 400);
DISPLAY INVISIBLE (1650 400);
FORCEADD UNIVERSAL_POWER..1
(-525 625);
FORCEPROP 3 LASTPIN (-525 575) SIG_NAME P12V_AUX\g
J 0
(-515 585);
DISPLAY 0.659574 (-515 585);
PAINT MONO (-515 585);
DISPLAY INVISIBLE (-515 585);
FORCEPROP 1 LAST HDL_POWER P12V_AUX
J 1
(-525 675);
DISPLAY 0.723404 (-525 675);
PAINT GREEN (-525 675);
FORCEPROP 1 LAST PATH I12
J 0
(-475 650);
DISPLAY 0.872340 (-475 650);
PAINT AQUA (-475 650);
DISPLAY INVISIBLE (-475 650);
FORCEPROP 2 LAST CDS_LIB logical_power
J 0
(-525 625);
PAINT MONO (-525 625);
DISPLAY INVISIBLE (-525 625);
FORCEADD Q_RES..2
(-1100 3450);
FORCEPROP 1 LAST PART_NUMBER CS31002FB08
J 0
(-1075 3325);
DISPLAY 0.787234 (-1075 3325);
DISPLAY INVISIBLE (-1075 3325);
FORCEPROP 1 LAST PACK_TYPE 0402LF
J 0
(-1075 3275);
DISPLAY 0.787234 (-1075 3275);
FORCEPROP 1 LAST WATTAGE 1/16W
J 0
(-1075 3425);
DISPLAY 0.787234 (-1075 3425);
FORCEPROP 1 LAST VALUE 10K
J 0
(-1070 3525);
DISPLAY 0.787234 (-1070 3525);
FORCEPROP 1 LAST TOLERANCE 1%
J 0
(-1070 3475);
DISPLAY 0.787234 (-1070 3475);
FORCEPROP 1 LAST MATERIAL EMPTY
J 0
(-1075 3375);
DISPLAY 0.787234 (-1075 3375);
PAINT RED (-1075 3375);
FORCEPROP 1 LAST $LOCATION R4668
J 0
(-1070 3575);
DISPLAY 0.787234 (-1070 3575);
FORCEPROP 1 LASTPIN (-1100 3550) $PN 1
J 0
(-1095 3512);
DISPLAY 0.787234 (-1095 3512);
PAINT MONO (-1095 3512);
FORCEPROP 1 LASTPIN (-1100 3350) $PN 2
J 0
(-1095 3360);
DISPLAY 0.787234 (-1095 3360);
PAINT MONO (-1095 3360);
FORCEPROP 1 LAST PATH I13
J 0
(-1050 3625);
DISPLAY 0.978723 (-1050 3625);
PAINT WHITE (-1050 3625);
DISPLAY INVISIBLE (-1050 3625);
FORCEPROP 2 LAST CDS_LIB pure_quanta
J 0
(-1100 3450);
DISPLAY INVISIBLE (-1100 3450);
FORCEPROP 0 LAST CDS_LOCATION R4668
J 0
(-1050 3625);
DISPLAY 1.021277 (-1050 3625);
DISPLAY INVISIBLE (-1050 3625);
FORCEPROP 0 LAST $SEC 1
J 0
(-1050 3625);
DISPLAY 0.680851 (-1050 3625);
PAINT MONO (-1050 3625);
DISPLAY INVISIBLE (-1050 3625);
FORCEPROP 0 LAST CDS_SEC 1
J 0
(-1050 3625);
DISPLAY 1.021277 (-1050 3625);
DISPLAY INVISIBLE (-1050 3625);
FORCEADD Q_RES..2
(-1100 4050);
FORCEPROP 1 LAST PART_NUMBER CS41602FB05
J 0
(-1050 3950);
DISPLAY 0.808511 (-1050 3950);
DISPLAY INVISIBLE (-1050 3950);
FORCEPROP 1 LAST PACK_TYPE 0402LF
J 0
(-1050 3900);
DISPLAY 0.808511 (-1050 3900);
FORCEPROP 1 LAST WATTAGE 1/16W
J 0
(-1050 4050);
DISPLAY 0.808511 (-1050 4050);
FORCEPROP 1 LAST VALUE 160K
J 0
(-1050 4150);
DISPLAY 0.808511 (-1050 4150);
FORCEPROP 1 LAST TOLERANCE 1%
J 0
(-1050 4100);
DISPLAY 0.808511 (-1050 4100);
FORCEPROP 1 LAST MATERIAL EMPTY
J 0
(-1050 4000);
DISPLAY 0.808511 (-1050 4000);
PAINT RED (-1050 4000);
FORCEPROP 1 LAST $LOCATION R4667
J 0
(-1050 4200);
DISPLAY 0.808511 (-1050 4200);
FORCEPROP 1 LASTPIN (-1100 4150) $PN 1
J 0
(-1095 4112);
DISPLAY 0.787234 (-1095 4112);
PAINT MONO (-1095 4112);
FORCEPROP 1 LASTPIN (-1100 3950) $PN 2
J 0
(-1095 3960);
DISPLAY 0.787234 (-1095 3960);
PAINT MONO (-1095 3960);
FORCEPROP 1 LAST PATH I14
J 0
(-1050 4225);
DISPLAY 0.978723 (-1050 4225);
PAINT WHITE (-1050 4225);
DISPLAY INVISIBLE (-1050 4225);
FORCEPROP 2 LAST CDS_LIB pure_quanta
J 0
(-1100 4050);
DISPLAY INVISIBLE (-1100 4050);
FORCEPROP 0 LAST CDS_LOCATION R4667
J 0
(-1050 4250);
DISPLAY 1.021277 (-1050 4250);
DISPLAY INVISIBLE (-1050 4250);
FORCEPROP 0 LAST $SEC 1
J 0
(-1050 4250);
DISPLAY 0.680851 (-1050 4250);
PAINT MONO (-1050 4250);
DISPLAY INVISIBLE (-1050 4250);
FORCEPROP 0 LAST CDS_SEC 1
J 0
(-1050 4250);
DISPLAY 1.021277 (-1050 4250);
DISPLAY INVISIBLE (-1050 4250);
FORCEADD UNIVERSAL_GND..1
(75 -775);
FORCEPROP 3 LASTPIN (75 -725) SIG_NAME GND\g
J 0
(85 -715);
DISPLAY 0.659574 (85 -715);
PAINT MONO (85 -715);
DISPLAY INVISIBLE (85 -715);
FORCEPROP 1 LAST PATH I15
J 0
(150 -775);
DISPLAY 0.872340 (150 -775);
PAINT AQUA (150 -775);
DISPLAY INVISIBLE (150 -775);
FORCEPROP 1 LAST HDL_POWER GND
J 1
(100 -850);
DISPLAY 0.872340 (100 -850);
PAINT GREEN (100 -850);
DISPLAY INVISIBLE (100 -850);
FORCEPROP 2 LAST CDS_LIB logical_power
J 0
(75 -775);
DISPLAY INVISIBLE (75 -775);
FORCEADD Q_RES..2
(75 -475);
FORCEPROP 1 LAST PART_NUMBER CS21002FB06
J 0
(115 -600);
DISPLAY 0.723404 (115 -600);
PAINT WHITE (115 -600);
DISPLAY INVISIBLE (115 -600);
FORCEPROP 1 LAST WATTAGE 1/16W
J 0
(115 -500);
DISPLAY 0.723404 (115 -500);
PAINT SKYBLUE (115 -500);
FORCEPROP 1 LAST VALUE 1K
J 0
(120 -400);
DISPLAY 0.723404 (120 -400);
PAINT SKYBLUE (120 -400);
FORCEPROP 1 LAST TOLERANCE 1%
J 0
(120 -450);
DISPLAY 0.723404 (120 -450);
PAINT SKYBLUE (120 -450);
FORCEPROP 1 LAST MATERIAL CHIP
J 0
(115 -550);
DISPLAY 0.723404 (115 -550);
PAINT SKYBLUE (115 -550);
FORCEPROP 1 LAST PACK_TYPE 0402LF
J 0
(115 -650);
DISPLAY 0.723404 (115 -650);
PAINT SKYBLUE (115 -650);
FORCEPROP 1 LAST LOCATION R2222
J 0
(120 -350);
DISPLAY 0.723404 (120 -350);
PAINT AQUA (120 -350);
FORCEPROP 1 LASTPIN (75 -375) $PN 1
J 0
(80 -413);
DISPLAY 0.723404 (80 -413);
PAINT MONO (80 -413);
FORCEPROP 1 LASTPIN (75 -575) $PN 2
J 0
(80 -565);
DISPLAY 0.723404 (80 -565);
PAINT MONO (80 -565);
FORCEPROP 1 LAST PATH I17
J 0
(125 -300);
DISPLAY 0.978723 (125 -300);
PAINT WHITE (125 -300);
DISPLAY INVISIBLE (125 -300);
FORCEPROP 2 LAST CDS_LIB pure_quanta
J 0
(75 -475);
DISPLAY INVISIBLE (75 -475);
FORCEPROP 2 LAST $SEC 1
J 0
(125 -250);
DISPLAY 0.680851 (125 -250);
PAINT MONO (125 -250);
DISPLAY INVISIBLE (125 -250);
FORCEPROP 0 LAST CDS_SEC 1
J 0
(125 -250);
DISPLAY 0.680851 (125 -250);
PAINT MONO (125 -250);
DISPLAY INVISIBLE (125 -250);
FORCEADD UNIVERSAL_GND..1
(550 25);
FORCEPROP 3 LASTPIN (550 75) SIG_NAME GND\g
J 0
(560 85);
DISPLAY 0.659574 (560 85);
PAINT MONO (560 85);
DISPLAY INVISIBLE (560 85);
FORCEPROP 1 LAST HDL_POWER GND
J 1
(575 -50);
DISPLAY 0.872340 (575 -50);
PAINT GREEN (575 -50);
DISPLAY INVISIBLE (575 -50);
FORCEPROP 1 LAST PATH I18
J 0
(625 25);
DISPLAY 0.872340 (625 25);
PAINT AQUA (625 25);
DISPLAY INVISIBLE (625 25);
FORCEPROP 2 LAST CDS_LIB logical_power
J 0
(550 25);
DISPLAY INVISIBLE (550 25);
FORCEADD Q_RES..2
(-2575 -1275);
FORCEPROP 1 LAST PART_NUMBER CS24992FB07
J 0
(-2535 -1400);
DISPLAY 0.638298 (-2535 -1400);
DISPLAY INVISIBLE (-2535 -1400);
FORCEPROP 1 LAST VALUE 4.99K
J 0
(-2530 -1200);
DISPLAY 0.638298 (-2530 -1200);
FORCEPROP 1 LAST TOLERANCE 1%
J 0
(-2530 -1250);
DISPLAY 0.638298 (-2530 -1250);
FORCEPROP 1 LAST WATTAGE 1/16W
J 0
(-2535 -1300);
DISPLAY 0.638298 (-2535 -1300);
FORCEPROP 1 LAST MATERIAL EMPTY
J 0
(-2535 -1350);
DISPLAY 0.638298 (-2535 -1350);
FORCEPROP 1 LAST PACK_TYPE 0402LF
J 0
(-2535 -1450);
DISPLAY 0.638298 (-2535 -1450);
FORCEPROP 1 LAST $LOCATION R2238
J 0
(-2530 -1150);
DISPLAY 0.638298 (-2530 -1150);
FORCEPROP 1 LASTPIN (-2575 -1175) $PN 1
J 0
(-2570 -1213);
DISPLAY 0.787234 (-2570 -1213);
PAINT MONO (-2570 -1213);
FORCEPROP 1 LASTPIN (-2575 -1375) $PN 2
J 0
(-2570 -1365);
DISPLAY 0.787234 (-2570 -1365);
PAINT MONO (-2570 -1365);
FORCEPROP 2 LAST CDS_LIB pure_quanta
J 0
(-2575 -1275);
DISPLAY INVISIBLE (-2575 -1275);
FORCEPROP 1 LAST PATH I2
J 0
(-2525 -1100);
DISPLAY 0.978723 (-2525 -1100);
PAINT WHITE (-2525 -1100);
DISPLAY INVISIBLE (-2525 -1100);
FORCEPROP 0 LAST CDS_LOCATION R2238
J 0
(-2525 -1100);
DISPLAY 1.021277 (-2525 -1100);
DISPLAY INVISIBLE (-2525 -1100);
FORCEPROP 0 LAST $SEC 1
J 0
(-2525 -1100);
DISPLAY 0.680851 (-2525 -1100);
PAINT MONO (-2525 -1100);
DISPLAY INVISIBLE (-2525 -1100);
FORCEPROP 0 LAST CDS_SEC 1
J 0
(-2525 -1100);
DISPLAY INVISIBLE (-2525 -1100);
FORCEADD Q_RES..2
(75 275);
FORCEPROP 1 LAST PART_NUMBER CS32672FB03
J 0
(115 150);
DISPLAY 0.723404 (115 150);
PAINT WHITE (115 150);
DISPLAY INVISIBLE (115 150);
FORCEPROP 1 LAST WATTAGE 1/16W
J 0
(115 250);
DISPLAY 0.723404 (115 250);
PAINT SKYBLUE (115 250);
FORCEPROP 1 LAST TOLERANCE 1%
J 0
(120 300);
DISPLAY 0.723404 (120 300);
PAINT SKYBLUE (120 300);
FORCEPROP 1 LAST VALUE 26.7K
J 0
(120 350);
DISPLAY 0.723404 (120 350);
PAINT SKYBLUE (120 350);
FORCEPROP 1 LAST MATERIAL CHIP
J 0
(115 200);
DISPLAY 0.723404 (115 200);
PAINT SKYBLUE (115 200);
FORCEPROP 1 LAST PACK_TYPE 0402LF
J 0
(115 100);
DISPLAY 0.723404 (115 100);
PAINT SKYBLUE (115 100);
FORCEPROP 1 LAST LOCATION R2221
J 0
(120 400);
DISPLAY 0.723404 (120 400);
PAINT AQUA (120 400);
FORCEPROP 1 LASTPIN (75 375) $PN 1
J 0
(80 337);
DISPLAY 0.723404 (80 337);
PAINT MONO (80 337);
FORCEPROP 1 LASTPIN (75 175) $PN 2
J 0
(80 185);
DISPLAY 0.723404 (80 185);
PAINT MONO (80 185);
FORCEPROP 1 LAST PATH I20
J 0
(125 450);
DISPLAY 0.978723 (125 450);
PAINT WHITE (125 450);
DISPLAY INVISIBLE (125 450);
FORCEPROP 2 LAST CDS_LIB pure_quanta
J 0
(75 275);
DISPLAY INVISIBLE (75 275);
FORCEPROP 2 LAST $SEC 1
J 0
(125 500);
DISPLAY 0.680851 (125 500);
PAINT MONO (125 500);
DISPLAY INVISIBLE (125 500);
FORCEPROP 0 LAST CDS_SEC 1
J 0
(125 500);
DISPLAY 0.680851 (125 500);
PAINT MONO (125 500);
DISPLAY INVISIBLE (125 500);
FORCEADD UNIVERSAL_POWER..1
(75 625);
FORCEPROP 3 LASTPIN (75 575) SIG_NAME P12V_AUX\g
J 0
(85 585);
DISPLAY 0.659574 (85 585);
PAINT MONO (85 585);
DISPLAY INVISIBLE (85 585);
FORCEPROP 1 LAST HDL_POWER P12V_AUX
J 1
(75 675);
DISPLAY 0.723404 (75 675);
PAINT GREEN (75 675);
FORCEPROP 2 LAST CDS_LIB logical_power
J 0
(75 625);
PAINT MONO (75 625);
DISPLAY INVISIBLE (75 625);
FORCEPROP 1 LAST PATH I21
J 0
(125 650);
DISPLAY 0.872340 (125 650);
PAINT AQUA (125 650);
DISPLAY INVISIBLE (125 650);
FORCEADD UNIVERSAL_GND..1
(-550 3100);
FORCEPROP 3 LASTPIN (-550 3150) SIG_NAME GND\g
J 0
(-540 3160);
DISPLAY 0.659574 (-540 3160);
PAINT MONO (-540 3160);
DISPLAY INVISIBLE (-540 3160);
FORCEPROP 1 LAST PATH I23
J 0
(-475 3100);
DISPLAY 0.872340 (-475 3100);
PAINT AQUA (-475 3100);
DISPLAY INVISIBLE (-475 3100);
FORCEPROP 1 LAST HDL_POWER GND
J 1
(-525 3025);
DISPLAY 0.872340 (-525 3025);
PAINT GREEN (-525 3025);
DISPLAY INVISIBLE (-525 3025);
FORCEPROP 2 LAST CDS_LIB logical_power
J 0
(-550 3100);
DISPLAY INVISIBLE (-550 3100);
FORCEADD Q_RES..2
(-550 3450);
FORCEPROP 1 LAST PART_NUMBER CS31002FB08
J 0
(-510 3325);
DISPLAY 0.787234 (-510 3325);
DISPLAY INVISIBLE (-510 3325);
FORCEPROP 1 LAST TOLERANCE 1%
J 0
(-505 3475);
DISPLAY 0.787234 (-505 3475);
FORCEPROP 1 LAST MATERIAL EMPTY
J 0
(-510 3375);
DISPLAY 0.787234 (-510 3375);
PAINT RED (-510 3375);
FORCEPROP 1 LAST VALUE 10K
J 0
(-505 3525);
DISPLAY 0.787234 (-505 3525);
FORCEPROP 1 LAST WATTAGE 1/16W
J 0
(-510 3425);
DISPLAY 0.787234 (-510 3425);
FORCEPROP 1 LAST PACK_TYPE 0402LF
J 0
(-510 3275);
DISPLAY 0.787234 (-510 3275);
FORCEPROP 1 LAST $LOCATION R4670
J 0
(-505 3575);
DISPLAY 0.787234 (-505 3575);
FORCEPROP 1 LASTPIN (-550 3550) $PN 1
J 0
(-545 3512);
DISPLAY 0.787234 (-545 3512);
PAINT MONO (-545 3512);
FORCEPROP 1 LASTPIN (-550 3350) $PN 2
J 0
(-545 3360);
DISPLAY 0.787234 (-545 3360);
PAINT MONO (-545 3360);
FORCEPROP 1 LAST PATH I24
J 0
(-500 3625);
DISPLAY 0.978723 (-500 3625);
PAINT WHITE (-500 3625);
DISPLAY INVISIBLE (-500 3625);
FORCEPROP 2 LAST CDS_LIB pure_quanta
J 0
(-550 3450);
DISPLAY INVISIBLE (-550 3450);
FORCEPROP 0 LAST CDS_LOCATION R4670
J 0
(-500 3625);
DISPLAY 1.021277 (-500 3625);
DISPLAY INVISIBLE (-500 3625);
FORCEPROP 0 LAST $SEC 1
J 0
(-500 3625);
DISPLAY 0.680851 (-500 3625);
PAINT MONO (-500 3625);
DISPLAY INVISIBLE (-500 3625);
FORCEPROP 0 LAST CDS_SEC 1
J 0
(-500 3625);
DISPLAY 1.021277 (-500 3625);
DISPLAY INVISIBLE (-500 3625);
FORCEADD Q_RES..2
(-550 4050);
FORCEPROP 1 LAST PART_NUMBER CS41602FB05
J 0
(-500 3950);
DISPLAY 0.808511 (-500 3950);
DISPLAY INVISIBLE (-500 3950);
FORCEPROP 1 LAST VALUE 160K
J 0
(-500 4150);
DISPLAY 0.808511 (-500 4150);
FORCEPROP 1 LAST PACK_TYPE 0402LF
J 0
(-500 3900);
DISPLAY 0.808511 (-500 3900);
FORCEPROP 1 LAST WATTAGE 1/16W
J 0
(-500 4050);
DISPLAY 0.808511 (-500 4050);
FORCEPROP 1 LAST MATERIAL EMPTY
J 0
(-500 4000);
DISPLAY 0.808511 (-500 4000);
PAINT RED (-500 4000);
FORCEPROP 1 LAST TOLERANCE 1%
J 0
(-500 4100);
DISPLAY 0.808511 (-500 4100);
FORCEPROP 1 LAST $LOCATION R4669
J 0
(-500 4200);
DISPLAY 0.978723 (-500 4200);
FORCEPROP 1 LASTPIN (-550 4150) $PN 1
J 0
(-545 4112);
DISPLAY 0.787234 (-545 4112);
PAINT MONO (-545 4112);
FORCEPROP 1 LASTPIN (-550 3950) $PN 2
J 0
(-545 3960);
DISPLAY 0.787234 (-545 3960);
PAINT MONO (-545 3960);
FORCEPROP 1 LAST PATH I25
J 0
(-500 4225);
DISPLAY 0.978723 (-500 4225);
PAINT WHITE (-500 4225);
DISPLAY INVISIBLE (-500 4225);
FORCEPROP 2 LAST CDS_LIB pure_quanta
J 0
(-550 4050);
DISPLAY INVISIBLE (-550 4050);
FORCEPROP 0 LAST CDS_LOCATION R4669
J 0
(-500 4225);
DISPLAY 1.021277 (-500 4225);
DISPLAY INVISIBLE (-500 4225);
FORCEPROP 0 LAST $SEC 1
J 0
(-500 4225);
DISPLAY 0.680851 (-500 4225);
PAINT MONO (-500 4225);
DISPLAY INVISIBLE (-500 4225);
FORCEPROP 0 LAST CDS_SEC 1
J 0
(-500 4225);
DISPLAY 1.021277 (-500 4225);
DISPLAY INVISIBLE (-500 4225);
FORCEADD UNIVERSAL_GND..1
(0 3800);
FORCEPROP 3 LASTPIN (0 3850) SIG_NAME GND\g
J 0
(10 3860);
DISPLAY 0.659574 (10 3860);
PAINT MONO (10 3860);
DISPLAY INVISIBLE (10 3860);
FORCEPROP 1 LAST HDL_POWER GND
J 1
(25 3725);
DISPLAY 0.872340 (25 3725);
PAINT GREEN (25 3725);
DISPLAY INVISIBLE (25 3725);
FORCEPROP 2 LAST CDS_LIB logical_power
J 0
(0 3800);
DISPLAY INVISIBLE (0 3800);
FORCEPROP 1 LAST PATH I26
J 0
(75 3800);
DISPLAY 0.872340 (75 3800);
PAINT AQUA (75 3800);
DISPLAY INVISIBLE (75 3800);
FORCEADD Q_RES..1
(1000 3050);
FORCEPROP 1 LAST PART_NUMBER CS00002JB13
J 0
(950 3150);
DISPLAY 0.978723 (950 3150);
DISPLAY INVISIBLE (950 3150);
FORCEPROP 0 LAST ROOM HSC1_BOM2
J 0
(950 3250);
DISPLAY 1.021277 (950 3250);
FORCEPROP 1 LAST WATTAGE 1/16W
J 2
(1425 3050);
DISPLAY 0.978723 (1425 3050);
FORCEPROP 1 LAST PACK_TYPE 0402LF
J 0
(1700 3050);
DISPLAY 0.978723 (1700 3050);
FORCEPROP 1 LAST MATERIAL EMPTY
J 0
(1450 3050);
DISPLAY 0.978723 (1450 3050);
FORCEPROP 1 LAST TOLERANCE 5%
J 0
(800 3050);
DISPLAY 0.978723 (800 3050);
FORCEPROP 1 LAST VALUE 0
J 2
(775 3050);
DISPLAY 0.978723 (775 3050);
FORCEPROP 1 LAST $LOCATION R4693
J 0
(950 3100);
DISPLAY 0.978723 (950 3100);
FORCEPROP 1 LASTPIN (900 3050) $PN 1
J 0
(912 3062);
DISPLAY 0.787234 (912 3062);
PAINT MONO (912 3062);
FORCEPROP 1 LASTPIN (1100 3050) $PN 2
J 0
(1062 3062);
DISPLAY 0.787234 (1062 3062);
PAINT MONO (1062 3062);
FORCEPROP 2 LAST CDS_LIB pure_quanta
J 0
(1000 3050);
DISPLAY INVISIBLE (1000 3050);
FORCEPROP 1 LAST PATH I29
J 0
(950 3200);
DISPLAY 0.978723 (950 3200);
PAINT WHITE (950 3200);
DISPLAY INVISIBLE (950 3200);
FORCEPROP 0 LAST CDS_LOCATION R4693
J 0
(950 3200);
DISPLAY 1.021277 (950 3200);
DISPLAY INVISIBLE (950 3200);
FORCEPROP 0 LAST $SEC 1
J 0
(950 3200);
DISPLAY 0.680851 (950 3200);
PAINT MONO (950 3200);
DISPLAY INVISIBLE (950 3200);
FORCEPROP 0 LAST CDS_SEC 1
J 0
(950 3200);
DISPLAY 1.021277 (950 3200);
DISPLAY INVISIBLE (950 3200);
FORCEADD UNIVERSAL_GND..1
(-2025 -1275);
FORCEPROP 3 LASTPIN (-2025 -1225) SIG_NAME GND\g
J 0
(-2015 -1215);
DISPLAY 0.659574 (-2015 -1215);
PAINT MONO (-2015 -1215);
DISPLAY INVISIBLE (-2015 -1215);
FORCEPROP 1 LAST HDL_POWER GND
J 1
(-2000 -1350);
DISPLAY 0.872340 (-2000 -1350);
PAINT GREEN (-2000 -1350);
DISPLAY INVISIBLE (-2000 -1350);
FORCEPROP 1 LAST PATH I3
J 0
(-1950 -1275);
DISPLAY 0.872340 (-1950 -1275);
PAINT AQUA (-1950 -1275);
DISPLAY INVISIBLE (-1950 -1275);
FORCEPROP 2 LAST CDS_LIB logical_power
J 0
(-2025 -1275);
DISPLAY INVISIBLE (-2025 -1275);
FORCEADD TPS3700DDCR..1
(1075 3700);
FORCEPROP 1 LAST PART_NUMBER AL003700002
J 0
(856 3984);
DISPLAY 0.723404 (856 3984);
PAINT GREEN (856 3984);
DISPLAY INVISIBLE (856 3984);
FORCEPROP 2 LAST VALUE TPS3700DDCR
J 0
(850 4025);
DISPLAY 1.021277 (850 4025);
FORCEPROP 2 LAST PART_TYPE SMLF
J 0
(850 4150);
DISPLAY 1.021277 (850 4150);
FORCEPROP 1 LAST MATERIAL EMPTY
J 0
(856 3857);
DISPLAY 0.723404 (856 3857);
PAINT GREEN (856 3857);
FORCEPROP 1 LAST LOCATION U369
J 0
(850 4100);
DISPLAY 0.723404 (850 4100);
PAINT GREEN (850 4100);
FORCEPROP 0 LASTPIN (1450 3600) $PN 2
J 0
(1460 3610);
DISPLAY 0.680851 (1460 3610);
PAINT MONO (1460 3610);
FORCEPROP 0 LASTPIN (700 3750) $PN 3
J 2
(690 3760);
DISPLAY 0.680851 (690 3760);
PAINT MONO (690 3760);
FORCEPROP 0 LASTPIN (700 3650) $PN 4
J 2
(690 3660);
DISPLAY 0.680851 (690 3660);
PAINT MONO (690 3660);
FORCEPROP 0 LASTPIN (1450 3750) $PN 1
J 0
(1460 3760);
DISPLAY 0.680851 (1460 3760);
PAINT MONO (1460 3760);
FORCEPROP 0 LASTPIN (1450 3650) $PN 6
J 0
(1460 3660);
DISPLAY 0.680851 (1460 3660);
PAINT MONO (1460 3660);
FORCEPROP 0 LASTPIN (700 3800) $PN 5
J 2
(690 3810);
DISPLAY 0.680851 (690 3810);
PAINT MONO (690 3810);
FORCEPROP 2 LAST CDS_LIB pure_quanta
J 0
(1075 3700);
DISPLAY INVISIBLE (1075 3700);
FORCEPROP 1 LAST NEEDS_NO_SIZE TRUE
J 0
(1075 3700);
DISPLAY 0.723404 (1075 3700);
PAINT GREEN (1075 3700);
DISPLAY INVISIBLE (1075 3700);
FORCEPROP 1 LAST PATH I30
J 0
(1075 3700);
DISPLAY 0.723404 (1075 3700);
PAINT GREEN (1075 3700);
DISPLAY INVISIBLE (1075 3700);
FORCEPROP 1 LAST CDS_LMAN_SYM_OUTLINE -225,150,225,-150
J 0
(1075 3700);
DISPLAY 0.468085 (1075 3700);
PAINT GREEN (1075 3700);
DISPLAY INVISIBLE (1075 3700);
FORCEPROP 0 LAST $SEC 1
J 0
(850 4200);
DISPLAY 0.680851 (850 4200);
PAINT MONO (850 4200);
DISPLAY INVISIBLE (850 4200);
FORCEPROP 0 LAST CDS_SEC 1
J 0
(850 4250);
DISPLAY 1.021277 (850 4250);
DISPLAY INVISIBLE (850 4250);
FORCEADD OFFPAGE..4
R 2
(-1625 4325);
FORCEPROP 2 LAST $XR1 306 
J 0
(-2027 4325);
DISPLAY 0.638298 (-2027 4325);
PAINT MONO (-2027 4325);
FORCEPROP 2 LAST $XR0 305 
J 0
(-1907 4325);
DISPLAY 0.638298 (-1907 4325);
PAINT MONO (-1907 4325);
FORCEPROP 1 LAST COMMENT_BODY TRUE
J 2
(-1600 4225);
DISPLAY 0.872340 (-1600 4225);
PAINT GREEN (-1600 4225);
DISPLAY INVISIBLE (-1600 4225);
FORCEPROP 1 LAST OFFPAGE TRUE
J 2
(-1950 4200);
DISPLAY 0.872340 (-1950 4200);
PAINT GREEN (-1950 4200);
DISPLAY INVISIBLE (-1950 4200);
FORCEPROP 2 LAST PATH I31
J 0
(-1875 4375);
DISPLAY 1.021277 (-1875 4375);
DISPLAY INVISIBLE (-1875 4375);
FORCEPROP 2 LAST CDS_LIB standard
J 0
(-1625 4325);
DISPLAY INVISIBLE (-1625 4325);
FORCEADD Q_RES..1
(925 -1375);
FORCEPROP 1 LAST PART_NUMBER CS00002JB13
J 0
(750 -1250);
DISPLAY 0.723404 (750 -1250);
PAINT WHITE (750 -1250);
DISPLAY INVISIBLE (750 -1250);
FORCEPROP 1 LAST PACK_TYPE 0402LF
J 0
(1025 -1300);
DISPLAY 0.723404 (1025 -1300);
PAINT SKYBLUE (1025 -1300);
FORCEPROP 1 LAST MATERIAL EMPTY
J 0
(1050 -1350);
DISPLAY 0.723404 (1050 -1350);
PAINT RED (1050 -1350);
FORCEPROP 1 LAST WATTAGE 1/16W
J 2
(975 -1300);
DISPLAY 0.723404 (975 -1300);
PAINT SKYBLUE (975 -1300);
FORCEPROP 1 LAST VALUE 0
J 2
(1025 -1350);
DISPLAY 0.723404 (1025 -1350);
PAINT SKYBLUE (1025 -1350);
FORCEPROP 1 LAST TOLERANCE 5%
J 0
(725 -1300);
DISPLAY 0.723404 (725 -1300);
PAINT SKYBLUE (725 -1300);
FORCEPROP 1 LAST LOCATION R2330
J 0
(700 -1350);
DISPLAY 0.723404 (700 -1350);
PAINT AQUA (700 -1350);
FORCEPROP 2 LAST CDS_LIB pure_quanta
J 0
(925 -1375);
DISPLAY INVISIBLE (925 -1375);
FORCEPROP 1 LAST PATH I33
J 0
(875 -1225);
DISPLAY 0.978723 (875 -1225);
PAINT WHITE (875 -1225);
DISPLAY INVISIBLE (875 -1225);
FORCEPROP 0 LAST $SEC 1
J 0
(700 -1300);
DISPLAY INVISIBLE (700 -1300);
FORCEPROP 2 LAST CDS_SEC 1
J 0
(875 -1175);
DISPLAY 0.680851 (875 -1175);
DISPLAY INVISIBLE (875 -1175);
FORCEPROP 1 LASTPIN (825 -1375) $PN 1
J 0
(837 -1363);
DISPLAY 0.787234 (837 -1363);
PAINT MONO (837 -1363);
DISPLAY INVISIBLE (837 -1363);
FORCEPROP 1 LASTPIN (1025 -1375) $PN 2
J 0
(987 -1363);
DISPLAY 0.787234 (987 -1363);
PAINT MONO (987 -1363);
DISPLAY INVISIBLE (987 -1363);
FORCEADD OFFPAGE..2
(2075 -1375);
PAINT AQUA (2075 -1375);
FORCEPROP 2 LAST $XR3 214 
J 0
(2624 -1375);
DISPLAY 0.638298 (2624 -1375);
PAINT MONO (2624 -1375);
FORCEPROP 2 LAST $XR2 182 
J 0
(2504 -1375);
DISPLAY 0.638298 (2504 -1375);
PAINT MONO (2504 -1375);
FORCEPROP 2 LAST $XR1 307 
J 0
(2384 -1375);
DISPLAY 0.638298 (2384 -1375);
PAINT MONO (2384 -1375);
FORCEPROP 2 LAST $XR0 244 
J 0
(2264 -1375);
DISPLAY 0.638298 (2264 -1375);
PAINT MONO (2264 -1375);
FORCEPROP 1 LAST COMMENT_BODY TRUE
J 0
(2030 -1470);
DISPLAY 0.872340 (2030 -1470);
PAINT GREEN (2030 -1470);
DISPLAY INVISIBLE (2030 -1470);
FORCEPROP 1 LAST OFFPAGE TRUE
J 0
(2400 -1500);
DISPLAY 0.872340 (2400 -1500);
PAINT AQUA (2400 -1500);
DISPLAY INVISIBLE (2400 -1500);
FORCEPROP 2 LAST CDS_LIB standard
J 0
(2075 -1375);
DISPLAY INVISIBLE (2075 -1375);
FORCEPROP 2 LAST PATH I34
J 0
(2525 -1325);
DISPLAY 1.021277 (2525 -1325);
DISPLAY INVISIBLE (2525 -1325);
FORCEADD UNIVERSAL_GND..1
(2300 -450);
FORCEPROP 3 LASTPIN (2300 -400) SIG_NAME GND\g
J 0
(2310 -390);
DISPLAY 0.659574 (2310 -390);
PAINT MONO (2310 -390);
DISPLAY INVISIBLE (2310 -390);
FORCEPROP 1 LAST PATH I35
J 0
(2375 -450);
DISPLAY 0.872340 (2375 -450);
PAINT AQUA (2375 -450);
DISPLAY INVISIBLE (2375 -450);
FORCEPROP 1 LAST HDL_POWER GND
J 1
(2325 -525);
DISPLAY 0.872340 (2325 -525);
PAINT GREEN (2325 -525);
DISPLAY INVISIBLE (2325 -525);
FORCEPROP 2 LAST CDS_LIB logical_power
J 0
(2300 -450);
DISPLAY INVISIBLE (2300 -450);
FORCEADD OFFPAGE..2
(3575 -125);
FORCEPROP 2 LAST $XR1 215 
J 0
(3764 -161);
DISPLAY 0.638298 (3764 -161);
PAINT MONO (3764 -161);
FORCEPROP 2 LAST $XR0 307 
J 0
(3764 -125);
DISPLAY 0.638298 (3764 -125);
PAINT MONO (3764 -125);
FORCEPROP 2 LAST PATH I36
J 0
(3775 -75);
DISPLAY 1.021277 (3775 -75);
DISPLAY INVISIBLE (3775 -75);
FORCEPROP 1 LAST COMMENT_BODY TRUE
J 0
(3530 -220);
DISPLAY 0.872340 (3530 -220);
PAINT GREEN (3530 -220);
DISPLAY INVISIBLE (3530 -220);
FORCEPROP 1 LAST OFFPAGE TRUE
J 0
(3900 -250);
DISPLAY 0.872340 (3900 -250);
PAINT AQUA (3900 -250);
DISPLAY INVISIBLE (3900 -250);
FORCEPROP 2 LAST CDS_LIB standard
J 0
(3575 -125);
DISPLAY INVISIBLE (3575 -125);
FORCEADD UNIVERSAL_GND..1
(4050 -500);
FORCEPROP 3 LASTPIN (4050 -450) SIG_NAME GND\g
J 0
(4060 -440);
DISPLAY 0.659574 (4060 -440);
PAINT MONO (4060 -440);
DISPLAY INVISIBLE (4060 -440);
FORCEPROP 1 LAST PATH I37
J 0
(4125 -500);
DISPLAY 0.872340 (4125 -500);
PAINT AQUA (4125 -500);
DISPLAY INVISIBLE (4125 -500);
FORCEPROP 1 LAST HDL_POWER GND
J 1
(4075 -575);
DISPLAY 0.872340 (4075 -575);
PAINT GREEN (4075 -575);
DISPLAY INVISIBLE (4075 -575);
FORCEPROP 2 LAST CDS_LIB logical_power
J 0
(4050 -500);
DISPLAY INVISIBLE (4050 -500);
FORCEADD MOSFET_N..1
(4000 -125);
FORCEPROP 1 LAST PART_NUMBER BAM138K0000
J 0
(4172 -514);
DISPLAY 0.723404 (4172 -514);
PAINT GREEN (4172 -514);
DISPLAY INVISIBLE (4172 -514);
FORCEPROP 1 LAST MATERIAL IC
J 0
(4172 -594);
DISPLAY 0.723404 (4172 -594);
PAINT GREEN (4172 -594);
FORCEPROP 2 LAST PATH I38
J 0
(4175 -200);
DISPLAY 1.021277 (4175 -200);
FORCEPROP 2 LAST MANUF_PN BSS138K
J 0
(4175 -250);
DISPLAY 1.021277 (4175 -250);
FORCEPROP 1 LAST VALUE BSS138K
J 0
(4172 -354);
DISPLAY 0.723404 (4172 -354);
PAINT GREEN (4172 -354);
FORCEPROP 1 LAST $LOCATION U325
J 0
(4172 -434);
DISPLAY 0.723404 (4172 -434);
PAINT GREEN (4172 -434);
FORCEPROP 1 LASTPIN (4050 -25) $PN D
R 1
J 0
(4050 -32);
DISPLAY 0.659574 (4050 -32);
PAINT MONO (4050 -32);
FORCEPROP 1 LASTPIN (3900 -225) $PN G
J 2
(3910 -222);
DISPLAY 0.659574 (3910 -222);
PAINT MONO (3910 -222);
FORCEPROP 1 LASTPIN (4050 -325) $PN S
R 1
J 2
(4050 -312);
DISPLAY 0.659574 (4050 -312);
PAINT MONO (4050 -312);
FORCEPROP 1 LAST PACK_TYPE SMLF
J 0
(4025 -375);
DISPLAY 0.723404 (4025 -375);
PAINT GREEN (4025 -375);
DISPLAY INVISIBLE (4025 -375);
FORCEPROP 2 LAST CDS_LIB pure_quanta
J 0
(4000 -125);
DISPLAY INVISIBLE (4000 -125);
FORCEPROP 1 LAST CDS_LMAN_SYM_OUTLINE -50,50,100,-150
J 0
(4000 -125);
DISPLAY 0.468085 (4000 -125);
PAINT GREEN (4000 -125);
DISPLAY INVISIBLE (4000 -125);
FORCEPROP 0 LAST CDS_LOCATION U325
J 0
(4175 -200);
DISPLAY 1.021277 (4175 -200);
DISPLAY INVISIBLE (4175 -200);
FORCEPROP 0 LAST $SEC 1
J 0
(4175 -200);
DISPLAY 0.680851 (4175 -200);
PAINT MONO (4175 -200);
DISPLAY INVISIBLE (4175 -200);
FORCEPROP 0 LAST CDS_SEC 1
J 0
(4175 -200);
DISPLAY 1.021277 (4175 -200);
DISPLAY INVISIBLE (4175 -200);
FORCEADD Q_RES..2
(2400 250);
FORCEPROP 1 LAST PART_NUMBER CS31002FB08
J 0
(2440 125);
DISPLAY 0.723404 (2440 125);
PAINT WHITE (2440 125);
DISPLAY INVISIBLE (2440 125);
FORCEPROP 1 LAST VALUE 10K
J 0
(2445 325);
DISPLAY 0.723404 (2445 325);
PAINT SKYBLUE (2445 325);
FORCEPROP 1 LAST TOLERANCE 1%
J 0
(2445 275);
DISPLAY 0.723404 (2445 275);
PAINT SKYBLUE (2445 275);
FORCEPROP 1 LAST WATTAGE 1/16W
J 0
(2440 225);
DISPLAY 0.723404 (2440 225);
PAINT SKYBLUE (2440 225);
FORCEPROP 1 LAST MATERIAL CHIP
J 0
(2440 175);
DISPLAY 0.723404 (2440 175);
PAINT SKYBLUE (2440 175);
FORCEPROP 1 LAST PACK_TYPE 0402LF
J 0
(2450 125);
DISPLAY 0.723404 (2450 125);
PAINT SKYBLUE (2450 125);
FORCEPROP 1 LAST LOCATION R2230
J 0
(2445 375);
DISPLAY 0.723404 (2445 375);
PAINT AQUA (2445 375);
FORCEPROP 1 LASTPIN (2400 350) $PN 1
J 0
(2405 312);
DISPLAY 0.723404 (2405 312);
PAINT WHITE (2405 312);
FORCEPROP 1 LASTPIN (2400 150) $PN 2
J 0
(2405 160);
DISPLAY 0.723404 (2405 160);
PAINT WHITE (2405 160);
FORCEPROP 1 LAST PATH I39
J 0
(2450 425);
DISPLAY 0.978723 (2450 425);
PAINT WHITE (2450 425);
DISPLAY INVISIBLE (2450 425);
FORCEPROP 2 LAST CDS_LIB pure_quanta
J 0
(2400 250);
DISPLAY INVISIBLE (2400 250);
FORCEPROP 2 LAST $SEC 1
J 0
(2450 475);
DISPLAY 0.680851 (2450 475);
PAINT MONO (2450 475);
DISPLAY INVISIBLE (2450 475);
FORCEPROP 2 LAST CDS_SEC 1
J 0
(2450 475);
DISPLAY 0.680851 (2450 475);
DISPLAY INVISIBLE (2450 475);
FORCEADD UNIVERSAL_POWER..1
(2400 625);
FORCEPROP 3 LASTPIN (2400 575) SIG_NAME P3V3_AUX\g
J 0
(2410 585);
DISPLAY 0.659574 (2410 585);
PAINT MONO (2410 585);
DISPLAY INVISIBLE (2410 585);
FORCEPROP 1 LAST HDL_POWER P3V3_AUX
J 1
(2400 675);
DISPLAY 0.723404 (2400 675);
PAINT GREEN (2400 675);
FORCEPROP 1 LAST PATH I40
J 0
(2450 650);
DISPLAY 0.872340 (2450 650);
PAINT AQUA (2450 650);
DISPLAY INVISIBLE (2450 650);
FORCEPROP 2 LAST CDS_LIB logical_power
J 0
(2400 625);
PAINT MONO (2400 625);
DISPLAY INVISIBLE (2400 625);
FORCEADD Q_RES..2
(2675 250);
FORCEPROP 1 LAST PART_NUMBER CS31002FB08
J 0
(2715 125);
DISPLAY 0.723404 (2715 125);
PAINT WHITE (2715 125);
DISPLAY INVISIBLE (2715 125);
FORCEPROP 1 LAST TOLERANCE 1%
J 0
(2720 275);
DISPLAY 0.723404 (2720 275);
PAINT SKYBLUE (2720 275);
FORCEPROP 1 LAST WATTAGE 1/16W
J 0
(2715 225);
DISPLAY 0.723404 (2715 225);
PAINT SKYBLUE (2715 225);
FORCEPROP 1 LAST MATERIAL CHIP
J 0
(2715 175);
DISPLAY 0.723404 (2715 175);
PAINT SKYBLUE (2715 175);
FORCEPROP 1 LAST VALUE 10K
J 0
(2720 325);
DISPLAY 0.723404 (2720 325);
PAINT SKYBLUE (2720 325);
FORCEPROP 1 LAST PACK_TYPE 0402LF
J 0
(2725 125);
DISPLAY 0.723404 (2725 125);
PAINT SKYBLUE (2725 125);
FORCEPROP 1 LAST LOCATION R2233
J 0
(2720 375);
DISPLAY 0.723404 (2720 375);
PAINT AQUA (2720 375);
FORCEPROP 1 LASTPIN (2675 350) $PN 1
J 0
(2680 312);
DISPLAY 0.723404 (2680 312);
PAINT WHITE (2680 312);
FORCEPROP 1 LASTPIN (2675 150) $PN 2
J 0
(2680 160);
DISPLAY 0.723404 (2680 160);
PAINT WHITE (2680 160);
FORCEPROP 1 LAST PATH I41
J 0
(2725 425);
DISPLAY 0.978723 (2725 425);
PAINT WHITE (2725 425);
DISPLAY INVISIBLE (2725 425);
FORCEPROP 2 LAST CDS_LIB pure_quanta
J 0
(2675 250);
DISPLAY INVISIBLE (2675 250);
FORCEPROP 2 LAST $SEC 1
J 0
(2725 475);
DISPLAY 0.680851 (2725 475);
PAINT MONO (2725 475);
DISPLAY INVISIBLE (2725 475);
FORCEPROP 2 LAST CDS_SEC 1
J 0
(2725 475);
DISPLAY 0.680851 (2725 475);
DISPLAY INVISIBLE (2725 475);
FORCEADD UNIVERSAL_GND..1
(1525 3475);
FORCEPROP 3 LASTPIN (1525 3525) SIG_NAME GND\g
J 0
(1535 3535);
DISPLAY 0.659574 (1535 3535);
PAINT MONO (1535 3535);
DISPLAY INVISIBLE (1535 3535);
FORCEPROP 1 LAST PATH I42
J 0
(1600 3475);
DISPLAY 0.872340 (1600 3475);
PAINT AQUA (1600 3475);
DISPLAY INVISIBLE (1600 3475);
FORCEPROP 1 LAST HDL_POWER GND
J 1
(1550 3400);
DISPLAY 0.872340 (1550 3400);
PAINT GREEN (1550 3400);
DISPLAY INVISIBLE (1550 3400);
FORCEPROP 2 LAST CDS_LIB logical_power
J 0
(1525 3475);
DISPLAY INVISIBLE (1525 3475);
FORCEADD UNIVERSAL_GND..1
(1975 3175);
FORCEPROP 3 LASTPIN (1975 3225) SIG_NAME GND\g
J 0
(1985 3235);
DISPLAY 0.659574 (1985 3235);
PAINT MONO (1985 3235);
DISPLAY INVISIBLE (1985 3235);
FORCEPROP 1 LAST PATH I43
J 0
(2050 3175);
DISPLAY 0.872340 (2050 3175);
PAINT AQUA (2050 3175);
DISPLAY INVISIBLE (2050 3175);
FORCEPROP 2 LAST CDS_LIB logical_power
J 0
(1975 3175);
DISPLAY INVISIBLE (1975 3175);
FORCEPROP 1 LAST HDL_POWER GND
J 1
(2000 3100);
DISPLAY 0.872340 (2000 3100);
PAINT GREEN (2000 3100);
DISPLAY INVISIBLE (2000 3100);
FORCEADD Q_RES..2
(1975 3400);
FORCEPROP 1 LAST PART_NUMBER CS00002JB13
J 0
(2015 3275);
DISPLAY 0.978723 (2015 3275);
DISPLAY INVISIBLE (2015 3275);
FORCEPROP 1 LAST TOLERANCE 5%
J 0
(2020 3425);
DISPLAY 0.978723 (2020 3425);
FORCEPROP 1 LAST PACK_TYPE 0402LF
J 0
(2015 3225);
DISPLAY 0.978723 (2015 3225);
FORCEPROP 1 LAST MATERIAL EMPTY
J 0
(2015 3325);
DISPLAY 0.978723 (2015 3325);
PAINT RED (2015 3325);
FORCEPROP 1 LAST WATTAGE 1/16W
J 0
(2025 3375);
DISPLAY 0.978723 (2025 3375);
FORCEPROP 1 LAST VALUE 0
J 0
(2020 3475);
DISPLAY 0.978723 (2020 3475);
FORCEPROP 1 LAST $LOCATION R4673
J 0
(2020 3525);
DISPLAY 0.978723 (2020 3525);
FORCEPROP 1 LASTPIN (1975 3500) $PN 1
J 0
(1980 3462);
DISPLAY 0.787234 (1980 3462);
PAINT MONO (1980 3462);
FORCEPROP 1 LASTPIN (1975 3300) $PN 2
J 0
(1980 3310);
DISPLAY 0.787234 (1980 3310);
PAINT MONO (1980 3310);
FORCEPROP 1 LAST PATH I44
J 0
(2025 3575);
DISPLAY 0.978723 (2025 3575);
PAINT WHITE (2025 3575);
DISPLAY INVISIBLE (2025 3575);
FORCEPROP 2 LAST CDS_LIB pure_quanta
J 0
(1975 3400);
DISPLAY INVISIBLE (1975 3400);
FORCEPROP 0 LAST CDS_LOCATION R4673
J 0
(2025 3575);
DISPLAY 1.021277 (2025 3575);
DISPLAY INVISIBLE (2025 3575);
FORCEPROP 0 LAST $SEC 1
J 0
(2025 3575);
DISPLAY 0.680851 (2025 3575);
PAINT MONO (2025 3575);
DISPLAY INVISIBLE (2025 3575);
FORCEPROP 0 LAST CDS_SEC 1
J 0
(2025 3575);
DISPLAY 1.021277 (2025 3575);
DISPLAY INVISIBLE (2025 3575);
FORCEADD Q_RES..2
(4050 450);
FORCEPROP 1 LAST PART_NUMBER CS24702JB10
J 0
(4100 350);
DISPLAY 0.638298 (4100 350);
DISPLAY INVISIBLE (4100 350);
FORCEPROP 1 LAST VALUE 4.7K
J 0
(4105 550);
DISPLAY 0.638298 (4105 550);
FORCEPROP 1 LAST TOLERANCE 5%
J 0
(4105 500);
DISPLAY 0.638298 (4105 500);
FORCEPROP 1 LAST WATTAGE 1/16W
J 0
(4100 450);
DISPLAY 0.638298 (4100 450);
FORCEPROP 1 LAST MATERIAL CHIP
J 0
(4100 400);
DISPLAY 0.638298 (4100 400);
FORCEPROP 1 LAST PACK_TYPE 0402LF
J 0
(4100 300);
DISPLAY 0.638298 (4100 300);
FORCEPROP 1 LAST $LOCATION R4620
J 0
(4105 600);
DISPLAY 0.638298 (4105 600);
FORCEPROP 1 LASTPIN (4050 550) $PN 1
J 0
(4055 512);
DISPLAY 0.787234 (4055 512);
PAINT MONO (4055 512);
FORCEPROP 1 LASTPIN (4050 350) $PN 2
J 0
(4055 360);
DISPLAY 0.787234 (4055 360);
PAINT MONO (4055 360);
FORCEPROP 1 LAST PATH I45
J 0
(4100 625);
DISPLAY 0.978723 (4100 625);
PAINT WHITE (4100 625);
DISPLAY INVISIBLE (4100 625);
FORCEPROP 2 LAST CDS_LIB pure_quanta
J 0
(4050 450);
DISPLAY INVISIBLE (4050 450);
FORCEPROP 0 LAST CDS_LOCATION R4620
J 0
(4125 650);
DISPLAY 1.021277 (4125 650);
DISPLAY INVISIBLE (4125 650);
FORCEPROP 0 LAST $SEC 1
J 0
(4125 650);
DISPLAY 0.680851 (4125 650);
PAINT MONO (4125 650);
DISPLAY INVISIBLE (4125 650);
FORCEPROP 0 LAST CDS_SEC 1
J 0
(4125 650);
DISPLAY 1.021277 (4125 650);
DISPLAY INVISIBLE (4125 650);
FORCEADD MOSFET_NCH_GDS_ESD_PROTECTED..1
(2825 4100);
FORCEPROP 1 LAST PART_NUMBER BAM70020002
J 0
(2967 4012);
DISPLAY 0.723404 (2967 4012);
PAINT GREEN (2967 4012);
DISPLAY INVISIBLE (2967 4012);
FORCEPROP 2 LAST PART_TYPE SMLF
J 0
(2975 4150);
DISPLAY 1.021277 (2975 4150);
FORCEPROP 2 LAST VALUE 2N7002K
J 0
(2975 4100);
DISPLAY 1.021277 (2975 4100);
FORCEPROP 1 LAST MATERIAL EMPTY
J 0
(2967 3955);
DISPLAY 0.723404 (2967 3955);
PAINT RED (2967 3955);
FORCEPROP 1 LAST $LOCATION U329
J 0
(2967 4064);
DISPLAY 0.723404 (2967 4064);
PAINT GREEN (2967 4064);
FORCEPROP 0 LASTPIN (2850 4300) $PN D
R 1
J 0
(2840 4310);
DISPLAY 0.680851 (2840 4310);
PAINT MONO (2840 4310);
FORCEPROP 0 LASTPIN (2650 4100) $PN G
J 2
(2640 4110);
DISPLAY 0.680851 (2640 4110);
PAINT MONO (2640 4110);
FORCEPROP 0 LASTPIN (2850 3900) $PN S
R 1
J 2
(2840 3890);
DISPLAY 0.680851 (2840 3890);
PAINT MONO (2840 3890);
FORCEPROP 1 LAST PATH I46
J 0
(2950 3950);
DISPLAY 0.723404 (2950 3950);
PAINT GREEN (2950 3950);
DISPLAY INVISIBLE (2950 3950);
FORCEPROP 2 LAST CDS_LIB pure_quanta
J 0
(2825 4100);
DISPLAY INVISIBLE (2825 4100);
FORCEPROP 1 LAST CDS_LMAN_SYM_OUTLINE -125,150,125,-150
J 0
(2825 4100);
DISPLAY 0.468085 (2825 4100);
PAINT GREEN (2825 4100);
DISPLAY INVISIBLE (2825 4100);
FORCEPROP 1 LAST NEEDS_NO_SIZE TRUE
J 0
(2950 3990);
DISPLAY 0.723404 (2950 3990);
PAINT GREEN (2950 3990);
DISPLAY INVISIBLE (2950 3990);
FORCEPROP 0 LAST CDS_LOCATION U329
J 0
(2975 4200);
DISPLAY 1.021277 (2975 4200);
DISPLAY INVISIBLE (2975 4200);
FORCEPROP 0 LAST $SEC 1
J 0
(2975 4200);
DISPLAY 0.680851 (2975 4200);
PAINT MONO (2975 4200);
DISPLAY INVISIBLE (2975 4200);
FORCEPROP 0 LAST CDS_SEC 1
J 0
(2975 4200);
DISPLAY 1.021277 (2975 4200);
DISPLAY INVISIBLE (2975 4200);
FORCEADD UNIVERSAL_GND..1
(2850 3775);
FORCEPROP 3 LASTPIN (2850 3825) SIG_NAME GND\g
J 0
(2860 3835);
DISPLAY 0.659574 (2860 3835);
PAINT MONO (2860 3835);
DISPLAY INVISIBLE (2860 3835);
FORCEPROP 1 LAST PATH I47
J 0
(2925 3775);
DISPLAY 0.872340 (2925 3775);
PAINT AQUA (2925 3775);
DISPLAY INVISIBLE (2925 3775);
FORCEPROP 2 LAST CDS_LIB logical_power
J 0
(2850 3775);
DISPLAY INVISIBLE (2850 3775);
FORCEPROP 1 LAST HDL_POWER GND
J 1
(2875 3700);
DISPLAY 0.872340 (2875 3700);
PAINT GREEN (2875 3700);
DISPLAY INVISIBLE (2875 3700);
FORCEADD Q_RES..2
(3575 3975);
FORCEPROP 1 LAST PART_NUMBER CS00002JB13
J 0
(3615 3850);
DISPLAY 0.978723 (3615 3850);
DISPLAY INVISIBLE (3615 3850);
FORCEPROP 1 LAST MATERIAL EMPTY
J 0
(3615 3900);
DISPLAY 0.978723 (3615 3900);
PAINT RED (3615 3900);
FORCEPROP 1 LAST WATTAGE 1/16W
J 0
(3625 3950);
DISPLAY 0.978723 (3625 3950);
FORCEPROP 1 LAST PACK_TYPE 0402LF
J 0
(3615 3800);
DISPLAY 0.978723 (3615 3800);
FORCEPROP 1 LAST VALUE 0
J 0
(3620 4050);
DISPLAY 0.978723 (3620 4050);
FORCEPROP 1 LAST TOLERANCE 5%
J 0
(3620 4000);
DISPLAY 0.978723 (3620 4000);
FORCEPROP 1 LAST LOCATION R4652
J 0
(3620 4100);
DISPLAY 0.978723 (3620 4100);
FORCEPROP 1 LASTPIN (3575 4075) $PN 1
J 0
(3580 4037);
DISPLAY 0.787234 (3580 4037);
PAINT MONO (3580 4037);
FORCEPROP 1 LASTPIN (3575 3875) $PN 2
J 0
(3580 3885);
DISPLAY 0.787234 (3580 3885);
PAINT MONO (3580 3885);
FORCEPROP 1 LAST PATH I48
J 0
(3625 4150);
DISPLAY 0.978723 (3625 4150);
PAINT WHITE (3625 4150);
DISPLAY INVISIBLE (3625 4150);
FORCEPROP 2 LAST CDS_LIB pure_quanta
J 0
(3575 3975);
DISPLAY INVISIBLE (3575 3975);
FORCEPROP 0 LAST $SEC 1
J 0
(3625 4150);
DISPLAY 0.680851 (3625 4150);
PAINT MONO (3625 4150);
DISPLAY INVISIBLE (3625 4150);
FORCEPROP 0 LAST CDS_SEC 1
J 0
(3400 4150);
DISPLAY 1.021277 (3400 4150);
DISPLAY INVISIBLE (3400 4150);
FORCEADD OFFPAGE..2
(4250 3650);
FORCEPROP 2 LAST $XR1 215 
J 0
(4559 3650);
DISPLAY 0.638298 (4559 3650);
PAINT MONO (4559 3650);
FORCEPROP 2 LAST $XR0 301 
J 0
(4439 3650);
DISPLAY 0.638298 (4439 3650);
PAINT MONO (4439 3650);
FORCEPROP 2 LAST PATH I49
J 0
(4575 3700);
DISPLAY 1.021277 (4575 3700);
DISPLAY INVISIBLE (4575 3700);
FORCEPROP 1 LAST OFFPAGE TRUE
J 0
(4575 3525);
DISPLAY 0.872340 (4575 3525);
PAINT AQUA (4575 3525);
DISPLAY INVISIBLE (4575 3525);
FORCEPROP 1 LAST COMMENT_BODY TRUE
J 0
(4205 3555);
DISPLAY 0.872340 (4205 3555);
PAINT GREEN (4205 3555);
DISPLAY INVISIBLE (4205 3555);
FORCEPROP 2 LAST CDS_LIB standard
J 0
(4250 3650);
DISPLAY INVISIBLE (4250 3650);
FORCEADD TPS3700DDCR..1
(-725 -1425);
FORCEPROP 1 LAST PART_NUMBER AL003700002
J 0
(-944 -1141);
DISPLAY 0.723404 (-944 -1141);
PAINT GREEN (-944 -1141);
DISPLAY INVISIBLE (-944 -1141);
FORCEPROP 1 LAST MATERIAL EMPTY
J 0
(-944 -1268);
DISPLAY 0.723404 (-944 -1268);
PAINT GREEN (-944 -1268);
FORCEPROP 2 LAST VALUE TPS3700DDCR
J 0
(-975 -1100);
DISPLAY 1.021277 (-975 -1100);
FORCEPROP 2 LAST PART_TYPE SMLF
J 0
(-950 -925);
DISPLAY 1.021277 (-950 -925);
FORCEPROP 1 LAST $LOCATION U205
J 0
(-944 -994);
DISPLAY 0.723404 (-944 -994);
PAINT GREEN (-944 -994);
FORCEPROP 0 LASTPIN (-350 -1525) $PN 2
J 0
(-340 -1515);
DISPLAY 0.680851 (-340 -1515);
PAINT MONO (-340 -1515);
FORCEPROP 0 LASTPIN (-1100 -1375) $PN 3
J 2
(-1110 -1365);
DISPLAY 0.680851 (-1110 -1365);
PAINT MONO (-1110 -1365);
FORCEPROP 0 LASTPIN (-1100 -1475) $PN 4
J 2
(-1110 -1465);
DISPLAY 0.680851 (-1110 -1465);
PAINT MONO (-1110 -1465);
FORCEPROP 0 LASTPIN (-350 -1375) $PN 1
J 0
(-340 -1365);
DISPLAY 0.680851 (-340 -1365);
PAINT MONO (-340 -1365);
FORCEPROP 0 LASTPIN (-350 -1475) $PN 6
J 0
(-340 -1465);
DISPLAY 0.680851 (-340 -1465);
PAINT MONO (-340 -1465);
FORCEPROP 0 LASTPIN (-1100 -1325) $PN 5
J 2
(-1110 -1315);
DISPLAY 0.680851 (-1110 -1315);
PAINT MONO (-1110 -1315);
FORCEPROP 2 LAST CDS_LIB pure_quanta
J 0
(-725 -1425);
DISPLAY INVISIBLE (-725 -1425);
FORCEPROP 1 LAST NEEDS_NO_SIZE TRUE
J 0
(-725 -1425);
DISPLAY 0.723404 (-725 -1425);
PAINT GREEN (-725 -1425);
DISPLAY INVISIBLE (-725 -1425);
FORCEPROP 1 LAST PATH I5
J 0
(-725 -1425);
DISPLAY 0.723404 (-725 -1425);
PAINT GREEN (-725 -1425);
DISPLAY INVISIBLE (-725 -1425);
FORCEPROP 1 LAST CDS_LMAN_SYM_OUTLINE -225,150,225,-150
J 0
(-725 -1425);
DISPLAY 0.468085 (-725 -1425);
PAINT GREEN (-725 -1425);
DISPLAY INVISIBLE (-725 -1425);
FORCEPROP 0 LAST CDS_LOCATION U205
J 0
(-950 -875);
DISPLAY 1.021277 (-950 -875);
DISPLAY INVISIBLE (-950 -875);
FORCEPROP 0 LAST $SEC 1
J 0
(-950 -875);
DISPLAY 0.680851 (-950 -875);
PAINT MONO (-950 -875);
DISPLAY INVISIBLE (-950 -875);
FORCEPROP 0 LAST CDS_SEC 1
J 0
(-950 -875);
DISPLAY 1.021277 (-950 -875);
DISPLAY INVISIBLE (-950 -875);
FORCEADD OFFPAGE..2
(5300 200);
FORCEPROP 2 LAST $XR1 215 
J 0
(5609 200);
DISPLAY 0.638298 (5609 200);
PAINT MONO (5609 200);
FORCEPROP 2 LAST $XR0 307 
J 0
(5489 200);
DISPLAY 0.638298 (5489 200);
PAINT MONO (5489 200);
FORCEPROP 2 LAST PATH I50
J 0
(5500 250);
DISPLAY 1.021277 (5500 250);
DISPLAY INVISIBLE (5500 250);
FORCEPROP 2 LAST CDS_LIB standard
J 0
(5300 200);
DISPLAY INVISIBLE (5300 200);
FORCEPROP 1 LAST OFFPAGE TRUE
J 0
(5625 75);
DISPLAY 0.872340 (5625 75);
PAINT AQUA (5625 75);
DISPLAY INVISIBLE (5625 75);
FORCEPROP 1 LAST COMMENT_BODY TRUE
J 0
(5255 105);
DISPLAY 0.872340 (5255 105);
PAINT GREEN (5255 105);
DISPLAY INVISIBLE (5255 105);
FORCEADD Q_RES..2
(1675 4125);
FORCEPROP 1 LAST PART_NUMBER CS31002FB08
J 0
(1715 4000);
DISPLAY 0.723404 (1715 4000);
PAINT WHITE (1715 4000);
DISPLAY INVISIBLE (1715 4000);
FORCEPROP 1 LAST PACK_TYPE 0402LF
J 0
(1725 4000);
DISPLAY 0.723404 (1725 4000);
PAINT SKYBLUE (1725 4000);
FORCEPROP 1 LAST TOLERANCE 1%
J 0
(1720 4150);
DISPLAY 0.723404 (1720 4150);
PAINT SKYBLUE (1720 4150);
FORCEPROP 1 LAST VALUE 10K
J 0
(1720 4200);
DISPLAY 0.723404 (1720 4200);
PAINT SKYBLUE (1720 4200);
FORCEPROP 1 LAST MATERIAL EMPTY
J 0
(1715 4050);
DISPLAY 0.723404 (1715 4050);
PAINT RED (1715 4050);
FORCEPROP 1 LAST WATTAGE 1/16W
J 0
(1715 4100);
DISPLAY 0.723404 (1715 4100);
PAINT SKYBLUE (1715 4100);
FORCEPROP 1 LAST $LOCATION R4671
J 0
(1720 4250);
DISPLAY 0.723404 (1720 4250);
PAINT AQUA (1720 4250);
FORCEPROP 1 LASTPIN (1675 4225) $PN 1
J 0
(1680 4187);
DISPLAY 0.787234 (1680 4187);
PAINT MONO (1680 4187);
FORCEPROP 1 LASTPIN (1675 4025) $PN 2
J 0
(1680 4035);
DISPLAY 0.787234 (1680 4035);
PAINT MONO (1680 4035);
FORCEPROP 2 LAST CDS_LIB pure_quanta
J 0
(1675 4125);
DISPLAY INVISIBLE (1675 4125);
FORCEPROP 1 LAST PATH I51
J 0
(1725 4300);
DISPLAY 0.978723 (1725 4300);
PAINT WHITE (1725 4300);
DISPLAY INVISIBLE (1725 4300);
FORCEPROP 0 LAST CDS_LOCATION R4671
J 0
(1725 4300);
DISPLAY 1.021277 (1725 4300);
DISPLAY INVISIBLE (1725 4300);
FORCEPROP 0 LAST $SEC 1
J 0
(1725 4300);
DISPLAY 0.680851 (1725 4300);
PAINT MONO (1725 4300);
DISPLAY INVISIBLE (1725 4300);
FORCEPROP 0 LAST CDS_SEC 1
J 0
(1725 4300);
DISPLAY 1.021277 (1725 4300);
DISPLAY INVISIBLE (1725 4300);
FORCEADD UNIVERSAL_POWER..1
(1675 4500);
FORCEPROP 3 LASTPIN (1675 4450) SIG_NAME P3V3_AUX\g
J 0
(1685 4460);
DISPLAY 0.659574 (1685 4460);
PAINT MONO (1685 4460);
DISPLAY INVISIBLE (1685 4460);
FORCEPROP 1 LAST HDL_POWER P3V3_AUX
J 1
(1675 4550);
DISPLAY 0.723404 (1675 4550);
PAINT GREEN (1675 4550);
FORCEPROP 1 LAST PATH I52
J 0
(1725 4525);
DISPLAY 0.872340 (1725 4525);
PAINT AQUA (1725 4525);
DISPLAY INVISIBLE (1725 4525);
FORCEPROP 2 LAST CDS_LIB logical_power
J 0
(1675 4500);
DISPLAY INVISIBLE (1675 4500);
FORCEADD Q_RES..2
(1950 4125);
FORCEPROP 1 LAST PART_NUMBER CS31002FB08
J 0
(1990 4000);
DISPLAY 0.723404 (1990 4000);
PAINT WHITE (1990 4000);
DISPLAY INVISIBLE (1990 4000);
FORCEPROP 1 LAST PACK_TYPE 0402LF
J 0
(2000 4000);
DISPLAY 0.723404 (2000 4000);
PAINT SKYBLUE (2000 4000);
FORCEPROP 1 LAST MATERIAL EMPTY
J 0
(1990 4050);
DISPLAY 0.723404 (1990 4050);
PAINT RED (1990 4050);
FORCEPROP 1 LAST WATTAGE 1/16W
J 0
(1990 4100);
DISPLAY 0.723404 (1990 4100);
PAINT SKYBLUE (1990 4100);
FORCEPROP 1 LAST TOLERANCE 1%
J 0
(1995 4150);
DISPLAY 0.723404 (1995 4150);
PAINT SKYBLUE (1995 4150);
FORCEPROP 1 LAST VALUE 10K
J 0
(1995 4200);
DISPLAY 0.723404 (1995 4200);
PAINT SKYBLUE (1995 4200);
FORCEPROP 1 LAST $LOCATION R4672
J 0
(1995 4250);
DISPLAY 0.723404 (1995 4250);
PAINT AQUA (1995 4250);
FORCEPROP 1 LASTPIN (1950 4225) $PN 1
J 0
(1955 4187);
DISPLAY 0.787234 (1955 4187);
PAINT MONO (1955 4187);
FORCEPROP 1 LASTPIN (1950 4025) $PN 2
J 0
(1955 4035);
DISPLAY 0.787234 (1955 4035);
PAINT MONO (1955 4035);
FORCEPROP 1 LAST PATH I53
J 0
(2000 4300);
DISPLAY 0.978723 (2000 4300);
PAINT WHITE (2000 4300);
DISPLAY INVISIBLE (2000 4300);
FORCEPROP 2 LAST CDS_LIB pure_quanta
J 0
(1950 4125);
DISPLAY INVISIBLE (1950 4125);
FORCEPROP 0 LAST CDS_LOCATION R4672
J 0
(2000 4300);
DISPLAY 1.021277 (2000 4300);
DISPLAY INVISIBLE (2000 4300);
FORCEPROP 0 LAST $SEC 1
J 0
(2000 4300);
DISPLAY 0.680851 (2000 4300);
PAINT MONO (2000 4300);
DISPLAY INVISIBLE (2000 4300);
FORCEPROP 0 LAST CDS_SEC 1
J 0
(2000 4300);
DISPLAY 1.021277 (2000 4300);
DISPLAY INVISIBLE (2000 4300);
FORCEADD UNIVERSAL_POWER..1
(4050 725);
FORCEPROP 3 LASTPIN (4050 675) SIG_NAME P3V3_AUX\g
J 0
(4060 685);
DISPLAY 0.659574 (4060 685);
PAINT MONO (4060 685);
DISPLAY INVISIBLE (4060 685);
FORCEPROP 1 LAST HDL_POWER P3V3_AUX
J 1
(4050 775);
DISPLAY 0.723404 (4050 775);
PAINT GREEN (4050 775);
FORCEPROP 1 LAST PATH I54
J 0
(4100 750);
DISPLAY 0.872340 (4100 750);
PAINT AQUA (4100 750);
DISPLAY INVISIBLE (4100 750);
FORCEPROP 2 LAST CDS_LIB logical_power
J 0
(4050 725);
DISPLAY INVISIBLE (4050 725);
FORCEADD UNIVERSAL_GND..1
(-1250 825);
FORCEPROP 3 LASTPIN (-1250 875) SIG_NAME GND\g
J 0
(-1240 885);
DISPLAY 0.659574 (-1240 885);
PAINT MONO (-1240 885);
DISPLAY INVISIBLE (-1240 885);
FORCEPROP 1 LAST HDL_POWER GND
J 1
(-1225 750);
DISPLAY 0.872340 (-1225 750);
PAINT GREEN (-1225 750);
DISPLAY INVISIBLE (-1225 750);
FORCEPROP 2 LAST CDS_LIB logical_power
J 0
(-1250 825);
DISPLAY INVISIBLE (-1250 825);
FORCEPROP 1 LAST PATH I55
J 0
(-1175 825);
DISPLAY 0.872340 (-1175 825);
PAINT AQUA (-1175 825);
DISPLAY INVISIBLE (-1175 825);
FORCEADD LM4040AIM3X25NOPB..1
(-875 1150);
FORCEPROP 1 LAST PART_NUMBER AL404025013
J 0
(-1078 1494);
DISPLAY 0.723404 (-1078 1494);
PAINT GREEN (-1078 1494);
DISPLAY INVISIBLE (-1078 1494);
FORCEPROP 1 LAST MATERIAL EMPTY
J 0
(-1078 1405);
DISPLAY 0.723404 (-1078 1405);
PAINT GREEN (-1078 1405);
FORCEPROP 2 LAST PART_TYPE SMLF
J 0
(-1075 1625);
DISPLAY 0.808511 (-1075 1625);
FORCEPROP 2 LAST VALUE LM4040AIM3X-2.5/NOPB
J 0
(-1075 1575);
DISPLAY 0.808511 (-1075 1575);
FORCEPROP 1 LAST $LOCATION U343
J 0
(-1078 1528);
DISPLAY 0.723404 (-1078 1528);
PAINT GREEN (-1078 1528);
FORCEPROP 0 LASTPIN (-1225 1300) $PN 1
J 2
(-1235 1310);
DISPLAY 0.680851 (-1235 1310);
PAINT MONO (-1235 1310);
FORCEPROP 0 LASTPIN (-1225 1000) $PN 2
J 2
(-1235 1010);
DISPLAY 0.680851 (-1235 1010);
PAINT MONO (-1235 1010);
FORCEPROP 0 LASTPIN (-525 1150) $PN 3
J 0
(-515 1160);
DISPLAY 0.680851 (-515 1160);
PAINT MONO (-515 1160);
FORCEPROP 1 LAST PATH I56
J 0
(-875 1150);
DISPLAY 0.723404 (-875 1150);
PAINT GREEN (-875 1150);
DISPLAY INVISIBLE (-875 1150);
FORCEPROP 2 LAST CDS_LIB pure_quanta
J 0
(-875 1150);
DISPLAY INVISIBLE (-875 1150);
FORCEPROP 1 LAST PIN_NAMES_ROTATE True
J 0
(-875 1150);
DISPLAY 0.489362 (-875 1150);
PAINT GREEN (-875 1150);
DISPLAY INVISIBLE (-875 1150);
FORCEPROP 1 LAST CDS_LMAN_SYM_OUTLINE -200,250,200,-250
J 0
(-875 1150);
DISPLAY 0.468085 (-875 1150);
PAINT GREEN (-875 1150);
DISPLAY INVISIBLE (-875 1150);
FORCEPROP 0 LAST CDS_LOCATION U343
J 0
(-1075 1675);
DISPLAY 1.021277 (-1075 1675);
DISPLAY INVISIBLE (-1075 1675);
FORCEPROP 0 LAST $SEC 1
J 0
(-1075 1675);
DISPLAY 0.680851 (-1075 1675);
PAINT MONO (-1075 1675);
DISPLAY INVISIBLE (-1075 1675);
FORCEPROP 0 LAST CDS_SEC 1
J 0
(-1075 1675);
DISPLAY 1.021277 (-1075 1675);
DISPLAY INVISIBLE (-1075 1675);
FORCEADD Q_RES..2
(-1275 1975);
FORCEPROP 1 LAST PART_NUMBER CS31002FB08
J 0
(-1235 1850);
DISPLAY 0.723404 (-1235 1850);
PAINT WHITE (-1235 1850);
DISPLAY INVISIBLE (-1235 1850);
FORCEPROP 1 LAST MATERIAL EMPTY
J 0
(-1235 1900);
DISPLAY 0.723404 (-1235 1900);
FORCEPROP 1 LAST WATTAGE 1/16W
J 0
(-1235 1950);
DISPLAY 0.723404 (-1235 1950);
FORCEPROP 1 LAST PACK_TYPE 0402LF
J 0
(-1225 1850);
DISPLAY 0.723404 (-1225 1850);
FORCEPROP 1 LAST VALUE 10K
J 0
(-1230 2050);
DISPLAY 0.723404 (-1230 2050);
FORCEPROP 1 LAST TOLERANCE 1%
J 0
(-1230 2000);
DISPLAY 0.723404 (-1230 2000);
FORCEPROP 1 LAST $LOCATION R4792
J 0
(-1230 2100);
DISPLAY 0.978723 (-1230 2100);
FORCEPROP 1 LASTPIN (-1275 2075) $PN 1
J 0
(-1270 2037);
DISPLAY 0.787234 (-1270 2037);
PAINT MONO (-1270 2037);
FORCEPROP 1 LASTPIN (-1275 1875) $PN 2
J 0
(-1270 1885);
DISPLAY 0.787234 (-1270 1885);
PAINT MONO (-1270 1885);
FORCEPROP 1 LAST PATH I57
J 0
(-1225 2150);
DISPLAY 0.978723 (-1225 2150);
PAINT WHITE (-1225 2150);
DISPLAY INVISIBLE (-1225 2150);
FORCEPROP 2 LAST CDS_LIB pure_quanta
J 0
(-1275 1975);
DISPLAY INVISIBLE (-1275 1975);
FORCEPROP 0 LAST CDS_LOCATION R4792
J 0
(-1225 2150);
DISPLAY 1.021277 (-1225 2150);
DISPLAY INVISIBLE (-1225 2150);
FORCEPROP 0 LAST $SEC 1
J 0
(-1225 2150);
DISPLAY 0.680851 (-1225 2150);
PAINT MONO (-1225 2150);
DISPLAY INVISIBLE (-1225 2150);
FORCEPROP 0 LAST CDS_SEC 1
J 0
(-1225 2150);
DISPLAY 1.021277 (-1225 2150);
DISPLAY INVISIBLE (-1225 2150);
FORCEADD UNIVERSAL_POWER..1
(-1275 2300);
FORCEPROP 3 LASTPIN (-1275 2250) SIG_NAME P3V3_AUX\g
J 0
(-1265 2260);
DISPLAY 0.659574 (-1265 2260);
PAINT MONO (-1265 2260);
DISPLAY INVISIBLE (-1265 2260);
FORCEPROP 1 LAST HDL_POWER P3V3_AUX
J 1
(-1275 2350);
DISPLAY 0.723404 (-1275 2350);
PAINT GREEN (-1275 2350);
FORCEPROP 2 LAST CDS_LIB logical_power
J 0
(-1275 2300);
DISPLAY INVISIBLE (-1275 2300);
FORCEPROP 1 LAST PATH I58
J 0
(-1225 2325);
DISPLAY 0.872340 (-1225 2325);
PAINT AQUA (-1225 2325);
DISPLAY INVISIBLE (-1225 2325);
FORCEADD UNIVERSAL_GND..1
(-275 1075);
FORCEPROP 3 LASTPIN (-275 1125) SIG_NAME GND\g
J 0
(-265 1135);
DISPLAY 0.659574 (-265 1135);
PAINT MONO (-265 1135);
DISPLAY INVISIBLE (-265 1135);
FORCEPROP 1 LAST PATH I59
J 0
(-200 1075);
DISPLAY 0.872340 (-200 1075);
PAINT AQUA (-200 1075);
DISPLAY INVISIBLE (-200 1075);
FORCEPROP 1 LAST HDL_POWER GND
J 1
(-250 1000);
DISPLAY 0.872340 (-250 1000);
PAINT GREEN (-250 1000);
DISPLAY INVISIBLE (-250 1000);
FORCEPROP 2 LAST CDS_LIB logical_power
J 0
(-275 1075);
DISPLAY INVISIBLE (-275 1075);
FORCEADD UNIVERSAL_GND..1
(-275 -1650);
FORCEPROP 3 LASTPIN (-275 -1600) SIG_NAME GND\g
J 0
(-265 -1590);
DISPLAY 0.659574 (-265 -1590);
PAINT MONO (-265 -1590);
DISPLAY INVISIBLE (-265 -1590);
FORCEPROP 1 LAST HDL_POWER GND
J 1
(-250 -1725);
DISPLAY 0.872340 (-250 -1725);
PAINT GREEN (-250 -1725);
DISPLAY INVISIBLE (-250 -1725);
FORCEPROP 2 LAST CDS_LIB logical_power
J 0
(-275 -1650);
DISPLAY INVISIBLE (-275 -1650);
FORCEPROP 1 LAST PATH I6
J 0
(-200 -1650);
DISPLAY 0.872340 (-200 -1650);
PAINT AQUA (-200 -1650);
DISPLAY INVISIBLE (-200 -1650);
FORCEADD UNIVERSAL_GND..1
(125 1075);
FORCEPROP 3 LASTPIN (125 1125) SIG_NAME GND\g
J 0
(135 1135);
DISPLAY 0.659574 (135 1135);
PAINT MONO (135 1135);
DISPLAY INVISIBLE (135 1135);
FORCEPROP 2 LAST CDS_LIB logical_power
J 0
(125 1075);
DISPLAY INVISIBLE (125 1075);
FORCEPROP 1 LAST HDL_POWER GND
J 1
(150 1000);
DISPLAY 0.872340 (150 1000);
PAINT GREEN (150 1000);
DISPLAY INVISIBLE (150 1000);
FORCEPROP 1 LAST PATH I63
J 0
(200 1075);
DISPLAY 0.872340 (200 1075);
PAINT AQUA (200 1075);
DISPLAY INVISIBLE (200 1075);
FORCEADD Q_CAP..1
R 2
(125 1350);
FORCEPROP 1 LAST PART_NUMBER CH4106K1B01
J 0
(200 1225);
DISPLAY 0.638298 (200 1225);
DISPLAY INVISIBLE (200 1225);
FORCEPROP 1 LAST MATERIAL EMPTY
J 0
(200 1250);
DISPLAY 0.638298 (200 1250);
PAINT RED (200 1250);
FORCEPROP 1 LAST TOLERANCE 10%
J 0
(200 1325);
DISPLAY 0.638298 (200 1325);
FORCEPROP 1 LAST VOLTAGE 50V
J 0
(200 1375);
DISPLAY 0.638298 (200 1375);
FORCEPROP 1 LAST VALUE 100NF
J 0
(200 1425);
DISPLAY 0.638298 (200 1425);
FORCEPROP 1 LAST PACK_TYPE C0402
J 0
(200 1175);
DISPLAY 0.638298 (200 1175);
FORCEPROP 1 LAST $LOCATION C2388
J 2
(325 1475);
DISPLAY 0.638298 (325 1475);
FORCEPROP 1 LASTPIN (125 1450) $PN 1
J 2
(115 1430);
DISPLAY 0.787234 (115 1430);
PAINT MONO (115 1430);
FORCEPROP 1 LASTPIN (125 1250) $PN 2
J 2
(115 1230);
DISPLAY 0.787234 (115 1230);
PAINT MONO (115 1230);
FORCEPROP 2 LAST CDS_LIB pure_quanta
J 0
(125 1350);
DISPLAY INVISIBLE (125 1350);
FORCEPROP 1 LAST PATH I64
J 2
(75 1500);
DISPLAY 0.978723 (75 1500);
PAINT WHITE (75 1500);
DISPLAY INVISIBLE (75 1500);
FORCEPROP 0 LAST CDS_LOCATION C2388
J 0
(250 1525);
DISPLAY 1.021277 (250 1525);
DISPLAY INVISIBLE (250 1525);
FORCEPROP 0 LAST $SEC 1
J 0
(250 1525);
DISPLAY 0.680851 (250 1525);
PAINT MONO (250 1525);
DISPLAY INVISIBLE (250 1525);
FORCEPROP 0 LAST CDS_SEC 1
J 0
(250 1525);
DISPLAY 1.021277 (250 1525);
DISPLAY INVISIBLE (250 1525);
FORCEADD UNIVERSAL_GND..1
(550 1075);
FORCEPROP 3 LASTPIN (550 1125) SIG_NAME GND\g
J 0
(560 1135);
DISPLAY 0.659574 (560 1135);
PAINT MONO (560 1135);
DISPLAY INVISIBLE (560 1135);
FORCEPROP 1 LAST HDL_POWER GND
J 1
(575 1000);
DISPLAY 0.872340 (575 1000);
PAINT GREEN (575 1000);
DISPLAY INVISIBLE (575 1000);
FORCEPROP 2 LAST CDS_LIB logical_power
J 0
(550 1075);
DISPLAY INVISIBLE (550 1075);
FORCEPROP 1 LAST PATH I65
J 0
(625 1075);
DISPLAY 0.872340 (625 1075);
PAINT AQUA (625 1075);
DISPLAY INVISIBLE (625 1075);
FORCEADD AP331AWG7..1
(900 1750);
FORCEPROP 1 LAST PART_NUMBER AL000331011
J 0
(1006 1559);
DISPLAY 0.723404 (1006 1559);
PAINT GREEN (1006 1559);
DISPLAY INVISIBLE (1006 1559);
FORCEPROP 2 LAST PART_TYPE SMLF
J 0
(1025 1700);
DISPLAY 1.021277 (1025 1700);
FORCEPROP 2 LAST VALUE AP331AWG-7
J 0
(1025 1650);
DISPLAY 1.021277 (1025 1650);
FORCEPROP 1 LAST MATERIAL EMPTY
J 0
(1000 1500);
DISPLAY 0.723404 (1000 1500);
PAINT GREEN (1000 1500);
FORCEPROP 1 LAST $LOCATION U344
J 0
(1006 1606);
DISPLAY 0.723404 (1006 1606);
PAINT GREEN (1006 1606);
FORCEPROP 0 LASTPIN (900 1500) $PN 2
R 1
J 2
(890 1490);
DISPLAY 0.680851 (890 1490);
PAINT MONO (890 1490);
FORCEPROP 0 LASTPIN (650 1800) $PN 3
J 2
(640 1810);
DISPLAY 0.680851 (640 1810);
PAINT MONO (640 1810);
FORCEPROP 0 LASTPIN (650 1700) $PN 1
J 2
(640 1710);
DISPLAY 0.680851 (640 1710);
PAINT MONO (640 1710);
FORCEPROP 0 LASTPIN (1150 1750) $PN 4
J 0
(1160 1760);
DISPLAY 0.680851 (1160 1760);
PAINT MONO (1160 1760);
FORCEPROP 0 LASTPIN (900 2000) $PN 5
R 1
J 0
(890 2010);
DISPLAY 0.680851 (890 2010);
PAINT MONO (890 2010);
FORCEPROP 1 LAST PATH I66
J 0
(900 1750);
DISPLAY 0.723404 (900 1750);
PAINT GREEN (900 1750);
DISPLAY INVISIBLE (900 1750);
FORCEPROP 2 LAST CDS_LIB pure_quanta
J 0
(900 1750);
DISPLAY INVISIBLE (900 1750);
FORCEPROP 1 LAST NEEDS_NO_SIZE TRUE
J 0
(900 1750);
DISPLAY 0.723404 (900 1750);
PAINT GREEN (900 1750);
DISPLAY INVISIBLE (900 1750);
FORCEPROP 1 LAST CDS_LMAN_SYM_OUTLINE -100,100,100,-100
J 0
(900 1750);
DISPLAY 0.468085 (900 1750);
PAINT GREEN (900 1750);
DISPLAY INVISIBLE (900 1750);
FORCEPROP 0 LAST CDS_LOCATION U344
J 0
(1025 1750);
DISPLAY 1.021277 (1025 1750);
DISPLAY INVISIBLE (1025 1750);
FORCEPROP 0 LAST $SEC 1
J 0
(1025 1750);
DISPLAY 0.680851 (1025 1750);
PAINT MONO (1025 1750);
DISPLAY INVISIBLE (1025 1750);
FORCEPROP 0 LAST CDS_SEC 1
J 0
(1025 1750);
DISPLAY 1.021277 (1025 1750);
DISPLAY INVISIBLE (1025 1750);
FORCEADD UNIVERSAL_GND..1
(900 1325);
FORCEPROP 3 LASTPIN (900 1375) SIG_NAME GND\g
J 0
(910 1385);
DISPLAY 0.659574 (910 1385);
PAINT MONO (910 1385);
DISPLAY INVISIBLE (910 1385);
FORCEPROP 1 LAST HDL_POWER GND
J 1
(925 1250);
DISPLAY 0.872340 (925 1250);
PAINT GREEN (925 1250);
DISPLAY INVISIBLE (925 1250);
FORCEPROP 2 LAST CDS_LIB logical_power
J 0
(900 1325);
DISPLAY INVISIBLE (900 1325);
FORCEPROP 1 LAST PATH I67
J 0
(975 1325);
DISPLAY 0.872340 (975 1325);
PAINT AQUA (975 1325);
DISPLAY INVISIBLE (975 1325);
FORCEADD Q_RES..1
(1350 2075);
FORCEPROP 1 LAST PART_NUMBER CS51002FB05
J 0
(1225 2125);
DISPLAY 0.638298 (1225 2125);
DISPLAY INVISIBLE (1225 2125);
FORCEPROP 1 LAST MATERIAL EMPTY
J 0
(1475 2075);
DISPLAY 0.638298 (1475 2075);
FORCEPROP 1 LAST PACK_TYPE 0402LF
J 0
(1975 2075);
DISPLAY 0.638298 (1975 2075);
FORCEPROP 1 LAST TOLERANCE 1%
J 0
(1625 2075);
DISPLAY 0.638298 (1625 2075);
FORCEPROP 1 LAST VALUE 1M
J 2
(1775 2075);
DISPLAY 0.638298 (1775 2075);
FORCEPROP 1 LAST WATTAGE 1/16W
J 2
(1950 2075);
DISPLAY 0.638298 (1950 2075);
FORCEPROP 1 LAST $LOCATION R4793
J 0
(1175 2075);
DISPLAY 0.638298 (1175 2075);
FORCEPROP 1 LASTPIN (1250 2075) $PN 1
J 0
(1262 2087);
DISPLAY 0.787234 (1262 2087);
PAINT MONO (1262 2087);
FORCEPROP 1 LASTPIN (1450 2075) $PN 2
J 0
(1412 2087);
DISPLAY 0.787234 (1412 2087);
PAINT MONO (1412 2087);
FORCEPROP 1 LAST PATH I68
J 0
(1300 2225);
DISPLAY 0.978723 (1300 2225);
PAINT WHITE (1300 2225);
DISPLAY INVISIBLE (1300 2225);
FORCEPROP 2 LAST CDS_LIB pure_quanta
J 0
(1350 2075);
DISPLAY INVISIBLE (1350 2075);
FORCEPROP 0 LAST CDS_LOCATION R4793
J 0
(1225 2175);
DISPLAY 1.021277 (1225 2175);
DISPLAY INVISIBLE (1225 2175);
FORCEPROP 0 LAST $SEC 1
J 0
(1225 2175);
DISPLAY 0.680851 (1225 2175);
PAINT MONO (1225 2175);
DISPLAY INVISIBLE (1225 2175);
FORCEPROP 0 LAST CDS_SEC 1
J 0
(1225 2175);
DISPLAY 1.021277 (1225 2175);
DISPLAY INVISIBLE (1225 2175);
FORCEADD UNIVERSAL_POWER..1
(900 2600);
FORCEPROP 3 LASTPIN (900 2550) SIG_NAME P12V_AUX\g
J 0
(910 2560);
DISPLAY 0.659574 (910 2560);
PAINT MONO (910 2560);
DISPLAY INVISIBLE (910 2560);
FORCEPROP 1 LAST HDL_POWER P12V_AUX
J 1
(900 2650);
DISPLAY 0.723404 (900 2650);
PAINT GREEN (900 2650);
FORCEPROP 2 LAST CDS_LIB logical_power
J 0
(900 2600);
DISPLAY INVISIBLE (900 2600);
FORCEPROP 1 LAST PATH I69
J 0
(950 2625);
DISPLAY 0.872340 (950 2625);
PAINT AQUA (950 2625);
DISPLAY INVISIBLE (950 2625);
FORCEADD Q_RES..2
(-2575 -875);
FORCEPROP 1 LAST PART_NUMBER CS41002FB09
J 0
(-2535 -1000);
DISPLAY 0.723404 (-2535 -1000);
PAINT WHITE (-2535 -1000);
DISPLAY INVISIBLE (-2535 -1000);
FORCEPROP 1 LAST VALUE 100K
J 0
(-2530 -800);
DISPLAY 0.723404 (-2530 -800);
PAINT SKYBLUE (-2530 -800);
FORCEPROP 1 LAST WATTAGE 1/16W
J 0
(-2535 -900);
DISPLAY 0.723404 (-2535 -900);
PAINT SKYBLUE (-2535 -900);
FORCEPROP 1 LAST PACK_TYPE 0402LF
J 0
(-2535 -1050);
DISPLAY 0.723404 (-2535 -1050);
PAINT SKYBLUE (-2535 -1050);
FORCEPROP 1 LAST TOLERANCE 1%
J 0
(-2530 -850);
DISPLAY 0.723404 (-2530 -850);
PAINT SKYBLUE (-2530 -850);
FORCEPROP 1 LAST MATERIAL EMPTY
J 0
(-2535 -950);
DISPLAY 0.723404 (-2535 -950);
PAINT SKYBLUE (-2535 -950);
FORCEPROP 1 LAST LOCATION R2236
J 0
(-2530 -750);
DISPLAY 0.723404 (-2530 -750);
PAINT AQUA (-2530 -750);
FORCEPROP 1 LASTPIN (-2575 -775) $PN 1
J 0
(-2570 -813);
DISPLAY 0.723404 (-2570 -813);
PAINT MONO (-2570 -813);
FORCEPROP 1 LASTPIN (-2575 -975) $PN 2
J 0
(-2570 -965);
DISPLAY 0.723404 (-2570 -965);
PAINT MONO (-2570 -965);
FORCEPROP 2 LAST CDS_LIB pure_quanta
J 0
(-2575 -875);
PAINT MONO (-2575 -875);
DISPLAY INVISIBLE (-2575 -875);
FORCEPROP 1 LAST PATH I7
J 0
(-2525 -700);
DISPLAY 0.978723 (-2525 -700);
PAINT WHITE (-2525 -700);
DISPLAY INVISIBLE (-2525 -700);
FORCEPROP 2 LAST $SEC 1
J 0
(-2525 -650);
DISPLAY 0.680851 (-2525 -650);
PAINT MONO (-2525 -650);
DISPLAY INVISIBLE (-2525 -650);
FORCEPROP 0 LAST CDS_SEC 1
J 0
(-2525 -650);
DISPLAY 0.680851 (-2525 -650);
PAINT MONO (-2525 -650);
DISPLAY INVISIBLE (-2525 -650);
FORCEADD UNIVERSAL_GND..1
(1150 2175);
FORCEPROP 3 LASTPIN (1150 2225) SIG_NAME GND\g
J 0
(1160 2235);
DISPLAY 0.659574 (1160 2235);
PAINT MONO (1160 2235);
DISPLAY INVISIBLE (1160 2235);
FORCEPROP 2 LAST CDS_LIB logical_power
J 0
(1150 2175);
DISPLAY INVISIBLE (1150 2175);
FORCEPROP 1 LAST HDL_POWER GND
J 1
(1175 2100);
DISPLAY 0.872340 (1175 2100);
PAINT GREEN (1175 2100);
DISPLAY INVISIBLE (1175 2100);
FORCEPROP 1 LAST PATH I70
J 0
(1225 2175);
DISPLAY 0.872340 (1225 2175);
PAINT AQUA (1225 2175);
DISPLAY INVISIBLE (1225 2175);
FORCEADD Q_CAP..1
R 2
(1150 2375);
FORCEPROP 1 LAST PART_NUMBER CH4106K1B01
J 0
(1225 2250);
DISPLAY 0.787234 (1225 2250);
DISPLAY INVISIBLE (1225 2250);
FORCEPROP 1 LAST VALUE 100NF
J 0
(1225 2450);
DISPLAY 0.787234 (1225 2450);
FORCEPROP 1 LAST VOLTAGE 50V
J 0
(1225 2400);
DISPLAY 0.787234 (1225 2400);
FORCEPROP 1 LAST TOLERANCE 10%
J 0
(1225 2350);
DISPLAY 0.787234 (1225 2350);
FORCEPROP 1 LAST MATERIAL EMPTY
J 0
(1225 2300);
DISPLAY 0.787234 (1225 2300);
FORCEPROP 1 LAST PACK_TYPE C0402
J 0
(1225 2200);
DISPLAY 0.787234 (1225 2200);
FORCEPROP 1 LAST $LOCATION C2390
J 0
(1225 2500);
DISPLAY 0.787234 (1225 2500);
FORCEPROP 1 LASTPIN (1150 2475) $PN 1
J 2
(1140 2455);
DISPLAY 0.787234 (1140 2455);
PAINT MONO (1140 2455);
FORCEPROP 1 LASTPIN (1150 2275) $PN 2
J 2
(1140 2255);
DISPLAY 0.787234 (1140 2255);
PAINT MONO (1140 2255);
FORCEPROP 1 LAST PATH I71
J 2
(1100 2525);
DISPLAY 0.978723 (1100 2525);
PAINT WHITE (1100 2525);
DISPLAY INVISIBLE (1100 2525);
FORCEPROP 2 LAST CDS_LIB pure_quanta
J 0
(1150 2375);
DISPLAY INVISIBLE (1150 2375);
FORCEPROP 0 LAST CDS_LOCATION C2390
J 0
(1225 2550);
DISPLAY 1.021277 (1225 2550);
DISPLAY INVISIBLE (1225 2550);
FORCEPROP 0 LAST $SEC 1
J 0
(1225 2550);
DISPLAY 0.680851 (1225 2550);
PAINT MONO (1225 2550);
DISPLAY INVISIBLE (1225 2550);
FORCEPROP 0 LAST CDS_SEC 1
J 0
(1225 2550);
DISPLAY 1.021277 (1225 2550);
DISPLAY INVISIBLE (1225 2550);
FORCEADD Q_RES..1
(2275 1750);
FORCEPROP 1 LAST PART_NUMBER CS03322FB03
J 0
(2175 1825);
DISPLAY 0.404255 (2175 1825);
DISPLAY INVISIBLE (2175 1825);
FORCEPROP 1 LAST TOLERANCE 1%
J 0
(2500 1750);
DISPLAY 0.510638 (2500 1750);
FORCEPROP 1 LAST VALUE 33.2
J 2
(2475 1750);
DISPLAY 0.510638 (2475 1750);
FORCEPROP 1 LAST $LOCATION R4794
J 0
(2000 1750);
DISPLAY 0.978723 (2000 1750);
FORCEPROP 1 LASTPIN (2175 1750) $PN 1
J 0
(2187 1762);
DISPLAY 0.787234 (2187 1762);
PAINT MONO (2187 1762);
FORCEPROP 1 LASTPIN (2375 1750) $PN 2
J 0
(2337 1762);
DISPLAY 0.787234 (2337 1762);
PAINT MONO (2337 1762);
FORCEPROP 1 LAST MATERIAL EMPTY
J 0
(2175 1850);
DISPLAY 0.404255 (2175 1850);
DISPLAY INVISIBLE (2175 1850);
FORCEPROP 1 LAST PATH I72
J 0
(2225 1900);
DISPLAY 0.978723 (2225 1900);
PAINT WHITE (2225 1900);
DISPLAY INVISIBLE (2225 1900);
FORCEPROP 1 LAST PACK_TYPE 0402LF
J 0
(2275 1850);
DISPLAY 0.404255 (2275 1850);
DISPLAY INVISIBLE (2275 1850);
FORCEPROP 1 LAST WATTAGE 1/16W
J 2
(2500 1850);
DISPLAY 0.404255 (2500 1850);
DISPLAY INVISIBLE (2500 1850);
FORCEPROP 2 LAST CDS_LIB pure_quanta
J 0
(2275 1750);
DISPLAY INVISIBLE (2275 1750);
FORCEPROP 0 LAST CDS_LOCATION R4794
J 0
(2125 1800);
DISPLAY 1.021277 (2125 1800);
DISPLAY INVISIBLE (2125 1800);
FORCEPROP 0 LAST $SEC 1
J 0
(2125 1800);
DISPLAY 0.680851 (2125 1800);
PAINT MONO (2125 1800);
DISPLAY INVISIBLE (2125 1800);
FORCEPROP 0 LAST CDS_SEC 1
J 0
(2125 1800);
DISPLAY 1.021277 (2125 1800);
DISPLAY INVISIBLE (2125 1800);
FORCEADD OFFPAGE..2
(3400 1750);
FORCEPROP 2 LAST $XR0 306 
J 0
(3589 1750);
DISPLAY 0.638298 (3589 1750);
PAINT MONO (3589 1750);
FORCEPROP 1 LAST COMMENT_BODY TRUE
J 0
(3355 1655);
DISPLAY 0.872340 (3355 1655);
PAINT GREEN (3355 1655);
DISPLAY INVISIBLE (3355 1655);
FORCEPROP 1 LAST OFFPAGE TRUE
J 0
(3725 1625);
DISPLAY 0.872340 (3725 1625);
PAINT AQUA (3725 1625);
DISPLAY INVISIBLE (3725 1625);
FORCEPROP 2 LAST CDS_LIB standard
J 0
(3400 1750);
DISPLAY INVISIBLE (3400 1750);
FORCEPROP 2 LAST PATH I73
J 0
(3725 1800);
DISPLAY 1.021277 (3725 1800);
DISPLAY INVISIBLE (3725 1800);
FORCEADD Q_CAP..1
R 2
(550 1350);
FORCEPROP 1 LAST PART_NUMBER CH4106K1B01
J 0
(625 1225);
DISPLAY 0.638298 (625 1225);
DISPLAY INVISIBLE (625 1225);
FORCEPROP 1 LAST PACK_TYPE C0402
J 0
(625 1175);
DISPLAY 0.638298 (625 1175);
FORCEPROP 1 LAST MATERIAL EMPTY
J 0
(625 1250);
DISPLAY 0.638298 (625 1250);
PAINT RED (625 1250);
FORCEPROP 1 LAST TOLERANCE 10%
J 0
(625 1325);
DISPLAY 0.638298 (625 1325);
FORCEPROP 1 LAST VALUE 100NF
J 0
(625 1425);
DISPLAY 0.638298 (625 1425);
FORCEPROP 1 LAST VOLTAGE 50V
J 0
(625 1375);
DISPLAY 0.638298 (625 1375);
FORCEPROP 1 LAST $LOCATION C2389
J 2
(775 1475);
DISPLAY 0.787234 (775 1475);
FORCEPROP 1 LASTPIN (550 1450) $PN 1
J 2
(540 1430);
DISPLAY 0.787234 (540 1430);
PAINT MONO (540 1430);
FORCEPROP 1 LASTPIN (550 1250) $PN 2
J 2
(540 1230);
DISPLAY 0.787234 (540 1230);
PAINT MONO (540 1230);
FORCEPROP 2 LAST CDS_LIB pure_quanta
J 0
(550 1350);
DISPLAY INVISIBLE (550 1350);
FORCEPROP 1 LAST PATH I76
J 2
(500 1500);
DISPLAY 0.978723 (500 1500);
PAINT WHITE (500 1500);
DISPLAY INVISIBLE (500 1500);
FORCEPROP 0 LAST CDS_LOCATION C2389
J 0
(675 1525);
DISPLAY 1.021277 (675 1525);
DISPLAY INVISIBLE (675 1525);
FORCEPROP 0 LAST $SEC 1
J 0
(675 1525);
DISPLAY 0.680851 (675 1525);
PAINT MONO (675 1525);
DISPLAY INVISIBLE (675 1525);
FORCEPROP 0 LAST CDS_SEC 1
J 0
(675 1525);
DISPLAY 1.021277 (675 1525);
DISPLAY INVISIBLE (675 1525);
FORCEADD Q_RES..2
(-275 1350);
FORCEPROP 1 LAST PART_NUMBER CS31002FB08
J 0
(-250 1225);
DISPLAY 0.787234 (-250 1225);
DISPLAY INVISIBLE (-250 1225);
FORCEPROP 1 LAST VALUE 10K
J 0
(-245 1425);
DISPLAY 0.787234 (-245 1425);
FORCEPROP 1 LAST MATERIAL EMPTY
J 0
(-250 1275);
DISPLAY 0.787234 (-250 1275);
PAINT RED (-250 1275);
FORCEPROP 1 LAST PACK_TYPE 0402LF
J 0
(-250 1175);
DISPLAY 0.787234 (-250 1175);
FORCEPROP 1 LAST WATTAGE 1/16W
J 0
(-250 1325);
DISPLAY 0.787234 (-250 1325);
FORCEPROP 1 LAST TOLERANCE 1%
J 0
(-245 1375);
DISPLAY 0.787234 (-245 1375);
FORCEPROP 1 LAST $LOCATION R4796
J 0
(-230 1475);
DISPLAY 0.978723 (-230 1475);
FORCEPROP 1 LASTPIN (-275 1450) $PN 1
J 0
(-270 1412);
DISPLAY 0.787234 (-270 1412);
PAINT MONO (-270 1412);
FORCEPROP 1 LASTPIN (-275 1250) $PN 2
J 0
(-270 1260);
DISPLAY 0.787234 (-270 1260);
PAINT MONO (-270 1260);
FORCEPROP 1 LAST PATH I77
J 0
(-225 1525);
DISPLAY 0.978723 (-225 1525);
PAINT WHITE (-225 1525);
DISPLAY INVISIBLE (-225 1525);
FORCEPROP 2 LAST CDS_LIB pure_quanta
J 0
(-275 1350);
DISPLAY INVISIBLE (-275 1350);
FORCEPROP 0 LAST CDS_LOCATION R4796
J 0
(-225 1525);
DISPLAY 1.021277 (-225 1525);
DISPLAY INVISIBLE (-225 1525);
FORCEPROP 0 LAST $SEC 1
J 0
(-225 1525);
DISPLAY 0.680851 (-225 1525);
PAINT MONO (-225 1525);
DISPLAY INVISIBLE (-225 1525);
FORCEPROP 0 LAST CDS_SEC 1
J 0
(-225 1525);
DISPLAY 1.021277 (-225 1525);
DISPLAY INVISIBLE (-225 1525);
FORCEADD Q_RES..2
(-275 2025);
FORCEPROP 1 LAST PART_NUMBER CS41602FB05
J 0
(-225 1925);
DISPLAY 0.808511 (-225 1925);
DISPLAY INVISIBLE (-225 1925);
FORCEPROP 1 LAST PACK_TYPE 0402LF
J 0
(-225 1875);
DISPLAY 0.808511 (-225 1875);
FORCEPROP 1 LAST VALUE 160K
J 0
(-225 2125);
DISPLAY 0.808511 (-225 2125);
FORCEPROP 1 LAST TOLERANCE 1%
J 0
(-225 2075);
DISPLAY 0.808511 (-225 2075);
FORCEPROP 1 LAST WATTAGE 1/16W
J 0
(-225 2025);
DISPLAY 0.808511 (-225 2025);
FORCEPROP 1 LAST MATERIAL EMPTY
J 0
(-225 1975);
DISPLAY 0.808511 (-225 1975);
PAINT RED (-225 1975);
FORCEPROP 1 LAST $LOCATION R4795
J 0
(-230 2150);
DISPLAY 0.978723 (-230 2150);
FORCEPROP 1 LASTPIN (-275 2125) $PN 1
J 0
(-270 2087);
DISPLAY 0.787234 (-270 2087);
PAINT MONO (-270 2087);
FORCEPROP 1 LASTPIN (-275 1925) $PN 2
J 0
(-270 1935);
DISPLAY 0.787234 (-270 1935);
PAINT MONO (-270 1935);
FORCEPROP 1 LAST PATH I78
J 0
(-225 2200);
DISPLAY 0.978723 (-225 2200);
PAINT WHITE (-225 2200);
DISPLAY INVISIBLE (-225 2200);
FORCEPROP 2 LAST CDS_LIB pure_quanta
J 0
(-275 2025);
DISPLAY INVISIBLE (-275 2025);
FORCEPROP 0 LAST CDS_LOCATION R4795
J 0
(-225 2200);
DISPLAY 1.021277 (-225 2200);
DISPLAY INVISIBLE (-225 2200);
FORCEPROP 0 LAST $SEC 1
J 0
(-225 2200);
DISPLAY 0.680851 (-225 2200);
PAINT MONO (-225 2200);
DISPLAY INVISIBLE (-225 2200);
FORCEPROP 0 LAST CDS_SEC 1
J 0
(-225 2200);
DISPLAY 1.021277 (-225 2200);
DISPLAY INVISIBLE (-225 2200);
FORCEADD OFFPAGE..4
R 2
(-725 2225);
FORCEPROP 2 LAST $XR1 306 
J 0
(-1127 2225);
DISPLAY 0.638298 (-1127 2225);
PAINT MONO (-1127 2225);
FORCEPROP 2 LAST $XR0 305 
J 0
(-1007 2225);
DISPLAY 0.638298 (-1007 2225);
PAINT MONO (-1007 2225);
FORCEPROP 1 LAST OFFPAGE TRUE
J 2
(-1050 2100);
DISPLAY 0.872340 (-1050 2100);
PAINT GREEN (-1050 2100);
DISPLAY INVISIBLE (-1050 2100);
FORCEPROP 1 LAST COMMENT_BODY TRUE
J 2
(-700 2125);
DISPLAY 0.872340 (-700 2125);
PAINT GREEN (-700 2125);
DISPLAY INVISIBLE (-700 2125);
FORCEPROP 2 LAST CDS_LIB standard
J 0
(-725 2225);
DISPLAY INVISIBLE (-725 2225);
FORCEPROP 2 LAST PATH I79
J 0
(-675 2300);
DISPLAY 1.021277 (-675 2300);
DISPLAY INVISIBLE (-675 2300);
FORCEADD UNIVERSAL_POWER..1
(-2575 -625);
FORCEPROP 3 LASTPIN (-2575 -675) SIG_NAME P12V_AUX\g
J 0
(-2565 -665);
DISPLAY 0.659574 (-2565 -665);
PAINT MONO (-2565 -665);
DISPLAY INVISIBLE (-2565 -665);
FORCEPROP 1 LAST HDL_POWER P12V_AUX
J 1
(-2575 -575);
DISPLAY 0.723404 (-2575 -575);
PAINT GREEN (-2575 -575);
FORCEPROP 2 LAST CDS_LIB logical_power
J 0
(-2575 -625);
PAINT MONO (-2575 -625);
DISPLAY INVISIBLE (-2575 -625);
FORCEPROP 1 LAST PATH I8
J 0
(-2525 -600);
DISPLAY 0.872340 (-2525 -600);
PAINT AQUA (-2525 -600);
DISPLAY INVISIBLE (-2525 -600);
FORCEADD Q_RES..2
(3100 2025);
FORCEPROP 1 LAST PART_NUMBER CS31002FB08
J 0
(3140 1900);
DISPLAY 0.723404 (3140 1900);
PAINT WHITE (3140 1900);
DISPLAY INVISIBLE (3140 1900);
FORCEPROP 1 LAST PACK_TYPE 0402LF
J 0
(3150 1900);
DISPLAY 0.723404 (3150 1900);
FORCEPROP 1 LAST MATERIAL EMPTY
J 0
(3140 1950);
DISPLAY 0.723404 (3140 1950);
FORCEPROP 1 LAST TOLERANCE 1%
J 0
(3145 2050);
DISPLAY 0.723404 (3145 2050);
FORCEPROP 1 LAST WATTAGE 1/16W
J 0
(3140 2000);
DISPLAY 0.723404 (3140 2000);
FORCEPROP 1 LAST VALUE 10K
J 0
(3145 2100);
DISPLAY 0.723404 (3145 2100);
FORCEPROP 1 LAST $LOCATION R4797
J 0
(3145 2150);
DISPLAY 0.978723 (3145 2150);
FORCEPROP 1 LASTPIN (3100 2125) $PN 1
J 0
(3105 2087);
DISPLAY 0.787234 (3105 2087);
PAINT MONO (3105 2087);
FORCEPROP 1 LASTPIN (3100 1925) $PN 2
J 0
(3105 1935);
DISPLAY 0.787234 (3105 1935);
PAINT MONO (3105 1935);
FORCEPROP 2 LAST CDS_LIB pure_quanta
J 0
(3100 2025);
DISPLAY INVISIBLE (3100 2025);
FORCEPROP 1 LAST PATH I80
J 0
(3150 2200);
DISPLAY 0.978723 (3150 2200);
PAINT WHITE (3150 2200);
DISPLAY INVISIBLE (3150 2200);
FORCEPROP 0 LAST CDS_LOCATION R4797
J 0
(3150 2200);
DISPLAY 1.021277 (3150 2200);
DISPLAY INVISIBLE (3150 2200);
FORCEPROP 0 LAST $SEC 1
J 0
(3150 2200);
DISPLAY 0.680851 (3150 2200);
PAINT MONO (3150 2200);
DISPLAY INVISIBLE (3150 2200);
FORCEPROP 0 LAST CDS_SEC 1
J 0
(3150 2200);
DISPLAY 1.021277 (3150 2200);
DISPLAY INVISIBLE (3150 2200);
FORCEADD UNIVERSAL_POWER..1
(3100 2350);
FORCEPROP 3 LASTPIN (3100 2300) SIG_NAME P3V3_AUX\g
J 0
(3110 2310);
DISPLAY 0.659574 (3110 2310);
PAINT MONO (3110 2310);
DISPLAY INVISIBLE (3110 2310);
FORCEPROP 1 LAST HDL_POWER P3V3_AUX
J 1
(3100 2400);
DISPLAY 0.723404 (3100 2400);
PAINT GREEN (3100 2400);
FORCEPROP 1 LAST PATH I81
J 0
(3150 2375);
DISPLAY 0.872340 (3150 2375);
PAINT AQUA (3150 2375);
DISPLAY INVISIBLE (3150 2375);
FORCEPROP 2 LAST CDS_LIB logical_power
J 0
(3100 2350);
DISPLAY INVISIBLE (3100 2350);
FORCEADD OFFPAGE..4
R 2
(2475 4100);
FORCEPROP 2 LAST $XR0 306 
J 0
(2223 4100);
DISPLAY 0.638298 (2223 4100);
PAINT MONO (2223 4100);
FORCEPROP 1 LAST OFFPAGE TRUE
J 2
(2150 3975);
DISPLAY 0.872340 (2150 3975);
PAINT GREEN (2150 3975);
DISPLAY INVISIBLE (2150 3975);
FORCEPROP 1 LAST COMMENT_BODY TRUE
J 2
(2500 4000);
DISPLAY 0.872340 (2500 4000);
PAINT GREEN (2500 4000);
DISPLAY INVISIBLE (2500 4000);
FORCEPROP 2 LAST PATH I82
J 0
(2525 4175);
DISPLAY 1.021277 (2525 4175);
DISPLAY INVISIBLE (2525 4175);
FORCEPROP 2 LAST CDS_LIB standard
J 0
(2475 4100);
DISPLAY INVISIBLE (2475 4100);
FORCEADD UNIVERSAL_POWER..1
(650 4650);
FORCEPROP 3 LASTPIN (650 4600) SIG_NAME P3V3_AUX\g
J 0
(660 4610);
DISPLAY 0.659574 (660 4610);
PAINT MONO (660 4610);
DISPLAY INVISIBLE (660 4610);
FORCEPROP 1 LAST HDL_POWER P3V3_AUX
J 1
(650 4700);
DISPLAY 0.723404 (650 4700);
PAINT GREEN (650 4700);
FORCEPROP 1 LAST PATH I84
J 0
(700 4675);
DISPLAY 0.872340 (700 4675);
PAINT AQUA (700 4675);
DISPLAY INVISIBLE (700 4675);
FORCEPROP 2 LAST CDS_LIB logical_power
J 0
(650 4650);
DISPLAY INVISIBLE (650 4650);
FORCEADD UNIVERSAL_POWER..1
(1275 900);
FORCEPROP 3 LASTPIN (1275 850) SIG_NAME P12V_AUX\g
J 0
(1285 860);
DISPLAY 0.659574 (1285 860);
PAINT MONO (1285 860);
DISPLAY INVISIBLE (1285 860);
FORCEPROP 1 LAST HDL_POWER P12V_AUX
J 1
(1275 950);
DISPLAY 0.723404 (1275 950);
PAINT GREEN (1275 950);
FORCEPROP 1 LAST PATH I86
J 0
(1325 925);
DISPLAY 0.872340 (1325 925);
PAINT AQUA (1325 925);
DISPLAY INVISIBLE (1325 925);
FORCEPROP 2 LAST CDS_LIB logical_power
J 0
(1275 900);
PAINT MONO (1275 900);
DISPLAY INVISIBLE (1275 900);
FORCEADD UNIVERSAL_POWER..1
(-1300 -425);
FORCEPROP 3 LASTPIN (-1300 -475) SIG_NAME P3V3_AUX\g
J 0
(-1290 -465);
DISPLAY 0.659574 (-1290 -465);
PAINT MONO (-1290 -465);
DISPLAY INVISIBLE (-1290 -465);
FORCEPROP 1 LAST HDL_POWER P3V3_AUX
J 1
(-1300 -375);
DISPLAY 0.723404 (-1300 -375);
PAINT GREEN (-1300 -375);
FORCEPROP 2 LAST CDS_LIB logical_power
J 0
(-1300 -425);
PAINT MONO (-1300 -425);
DISPLAY INVISIBLE (-1300 -425);
FORCEPROP 1 LAST PATH I87
J 0
(-1250 -400);
DISPLAY 0.872340 (-1250 -400);
PAINT AQUA (-1250 -400);
DISPLAY INVISIBLE (-1250 -400);
FORCEADD Q_CAP..1
(-2025 -1025);
FORCEPROP 1 LAST PART_NUMBER CH5104KEB02
J 0
(-1975 -1175);
DISPLAY 0.638298 (-1975 -1175);
DISPLAY INVISIBLE (-1975 -1175);
FORCEPROP 1 LAST TOLERANCE 10%
J 0
(-1975 -1075);
DISPLAY 0.638298 (-1975 -1075);
FORCEPROP 1 LAST MATERIAL EMPTY
J 0
(-1975 -1125);
DISPLAY 0.638298 (-1975 -1125);
PAINT RED (-1975 -1125);
FORCEPROP 1 LAST PACK_TYPE C0402
J 0
(-1975 -1225);
DISPLAY 0.638298 (-1975 -1225);
FORCEPROP 1 LAST VALUE 1UF
J 0
(-1975 -975);
DISPLAY 0.638298 (-1975 -975);
FORCEPROP 1 LAST VOLTAGE 25V
J 0
(-1975 -1025);
DISPLAY 0.638298 (-1975 -1025);
FORCEPROP 1 LAST LOCATION C1562
J 0
(-1975 -925);
DISPLAY 0.978723 (-1975 -925);
FORCEPROP 1 LASTPIN (-2025 -925) $PN 1
J 0
(-2015 -945);
DISPLAY 0.787234 (-2015 -945);
PAINT MONO (-2015 -945);
FORCEPROP 1 LASTPIN (-2025 -1125) $PN 2
J 0
(-2015 -1145);
DISPLAY 0.787234 (-2015 -1145);
PAINT MONO (-2015 -1145);
FORCEPROP 1 LAST PATH I89
J 0
(-1975 -875);
DISPLAY 0.978723 (-1975 -875);
PAINT WHITE (-1975 -875);
DISPLAY INVISIBLE (-1975 -875);
FORCEPROP 2 LAST CDS_LIB pure_quanta
J 0
(-2025 -1025);
DISPLAY INVISIBLE (-2025 -1025);
FORCEPROP 0 LAST $SEC 1
J 0
(-1975 -875);
DISPLAY 0.680851 (-1975 -875);
PAINT MONO (-1975 -875);
DISPLAY INVISIBLE (-1975 -875);
FORCEPROP 0 LAST CDS_SEC 1
J 0
(-1975 -875);
DISPLAY 1.021277 (-1975 -875);
DISPLAY INVISIBLE (-1975 -875);
FORCEADD UNIVERSAL_GND..1
(-525 -775);
FORCEPROP 3 LASTPIN (-525 -725) SIG_NAME GND\g
J 0
(-515 -715);
DISPLAY 0.659574 (-515 -715);
PAINT MONO (-515 -715);
DISPLAY INVISIBLE (-515 -715);
FORCEPROP 1 LAST PATH I9
J 0
(-450 -775);
DISPLAY 0.872340 (-450 -775);
PAINT AQUA (-450 -775);
DISPLAY INVISIBLE (-450 -775);
FORCEPROP 2 LAST CDS_LIB logical_power
J 0
(-525 -775);
DISPLAY INVISIBLE (-525 -775);
FORCEPROP 1 LAST HDL_POWER GND
J 1
(-500 -850);
DISPLAY 0.872340 (-500 -850);
PAINT GREEN (-500 -850);
DISPLAY INVISIBLE (-500 -850);
FORCEADD Q_CAP..1
(550 275);
FORCEPROP 1 LAST PART_NUMBER CH5104KEB02
J 0
(600 125);
DISPLAY 0.638298 (600 125);
DISPLAY INVISIBLE (600 125);
FORCEPROP 1 LAST VALUE 1UF
J 0
(600 325);
DISPLAY 0.638298 (600 325);
FORCEPROP 1 LAST PACK_TYPE C0402
J 0
(600 75);
DISPLAY 0.638298 (600 75);
FORCEPROP 1 LAST TOLERANCE 10%
J 0
(600 225);
DISPLAY 0.638298 (600 225);
FORCEPROP 1 LAST MATERIAL X6S
J 0
(600 175);
DISPLAY 0.638298 (600 175);
PAINT RED (600 175);
FORCEPROP 1 LAST VOLTAGE 25V
J 0
(600 275);
DISPLAY 0.638298 (600 275);
FORCEPROP 1 LAST LOCATION C1561
J 0
(600 375);
DISPLAY 0.978723 (600 375);
FORCEPROP 1 LASTPIN (550 375) $PN 1
J 0
(560 355);
DISPLAY 0.787234 (560 355);
PAINT MONO (560 355);
FORCEPROP 1 LASTPIN (550 175) $PN 2
J 0
(560 155);
DISPLAY 0.787234 (560 155);
PAINT MONO (560 155);
FORCEPROP 2 LAST CDS_LIB pure_quanta
J 0
(550 275);
DISPLAY INVISIBLE (550 275);
FORCEPROP 1 LAST PATH I90
J 0
(600 425);
DISPLAY 0.978723 (600 425);
PAINT WHITE (600 425);
DISPLAY INVISIBLE (600 425);
FORCEPROP 0 LAST $SEC 1
J 0
(600 425);
DISPLAY 0.680851 (600 425);
PAINT MONO (600 425);
DISPLAY INVISIBLE (600 425);
FORCEPROP 0 LAST CDS_SEC 1
J 0
(600 425);
DISPLAY 1.021277 (600 425);
DISPLAY INVISIBLE (600 425);
FORCEADD Q_CAP..1
(0 4100);
FORCEPROP 1 LAST PART_NUMBER CH5104KEB02
J 0
(50 3950);
DISPLAY 0.638298 (50 3950);
DISPLAY INVISIBLE (50 3950);
FORCEPROP 1 LAST PACK_TYPE C0402
J 0
(50 3900);
DISPLAY 0.638298 (50 3900);
FORCEPROP 1 LAST TOLERANCE 10%
J 0
(50 4050);
DISPLAY 0.638298 (50 4050);
FORCEPROP 1 LAST VALUE 1UF
J 0
(50 4150);
DISPLAY 0.638298 (50 4150);
FORCEPROP 1 LAST VOLTAGE 25V
J 0
(50 4100);
DISPLAY 0.638298 (50 4100);
FORCEPROP 1 LAST MATERIAL EMPTY
J 0
(50 4000);
DISPLAY 0.638298 (50 4000);
PAINT RED (50 4000);
FORCEPROP 1 LAST LOCATION C4562
J 0
(50 4200);
DISPLAY 0.978723 (50 4200);
FORCEPROP 1 LASTPIN (0 4200) $PN 1
J 0
(10 4180);
DISPLAY 0.787234 (10 4180);
PAINT MONO (10 4180);
FORCEPROP 1 LASTPIN (0 4000) $PN 2
J 0
(10 3980);
DISPLAY 0.787234 (10 3980);
PAINT MONO (10 3980);
FORCEPROP 1 LAST PATH I91
J 0
(50 4250);
DISPLAY 0.978723 (50 4250);
PAINT WHITE (50 4250);
DISPLAY INVISIBLE (50 4250);
FORCEPROP 2 LAST CDS_LIB pure_quanta
J 0
(0 4100);
DISPLAY INVISIBLE (0 4100);
FORCEPROP 0 LAST $SEC 1
J 0
(50 4250);
DISPLAY 0.680851 (50 4250);
PAINT MONO (50 4250);
DISPLAY INVISIBLE (50 4250);
FORCEPROP 0 LAST CDS_SEC 1
J 0
(50 4250);
DISPLAY 1.021277 (50 4250);
DISPLAY INVISIBLE (50 4250);
FORCEADD Q_CAP..1
(400 4100);
FORCEPROP 1 LAST PART_NUMBER CH4104K1B00
J 0
(450 3950);
DISPLAY 0.510638 (450 3950);
DISPLAY INVISIBLE (450 3950);
FORCEPROP 1 LAST TOLERANCE 10%
J 0
(450 4050);
DISPLAY 0.510638 (450 4050);
FORCEPROP 1 LAST PACK_TYPE 0402
J 0
(450 3900);
DISPLAY 0.510638 (450 3900);
FORCEPROP 1 LAST MATERIAL EMPTY
J 0
(450 4000);
DISPLAY 0.510638 (450 4000);
FORCEPROP 1 LAST VALUE 0.1UF
J 0
(450 4150);
DISPLAY 0.510638 (450 4150);
FORCEPROP 1 LAST VOLTAGE 25V
J 0
(450 4100);
DISPLAY 0.510638 (450 4100);
FORCEPROP 1 LAST $LOCATION C2393
J 0
(450 4200);
DISPLAY 0.978723 (450 4200);
FORCEPROP 1 LASTPIN (400 4200) $PN 1
J 0
(410 4180);
DISPLAY 0.787234 (410 4180);
PAINT MONO (410 4180);
FORCEPROP 1 LASTPIN (400 4000) $PN 2
J 0
(410 3980);
DISPLAY 0.787234 (410 3980);
PAINT MONO (410 3980);
FORCEPROP 2 LAST CDS_LIB pure_quanta
J 0
(400 4100);
DISPLAY INVISIBLE (400 4100);
FORCEPROP 1 LAST PATH I92
J 0
(450 4250);
DISPLAY 0.978723 (450 4250);
PAINT WHITE (450 4250);
DISPLAY INVISIBLE (450 4250);
FORCEPROP 0 LAST CDS_LOCATION C2393
J 0
(450 4250);
DISPLAY 1.021277 (450 4250);
DISPLAY INVISIBLE (450 4250);
FORCEPROP 0 LAST $SEC 1
J 0
(450 4250);
DISPLAY 0.680851 (450 4250);
PAINT MONO (450 4250);
DISPLAY INVISIBLE (450 4250);
FORCEPROP 0 LAST CDS_SEC 1
J 0
(450 4250);
DISPLAY 1.021277 (450 4250);
DISPLAY INVISIBLE (450 4250);
FORCEADD Q_CAP..1
(950 275);
FORCEPROP 1 LAST PART_NUMBER CH4104K1B00
J 0
(1000 125);
DISPLAY 0.510638 (1000 125);
DISPLAY INVISIBLE (1000 125);
FORCEPROP 1 LAST VOLTAGE 25V
J 0
(1000 275);
DISPLAY 0.510638 (1000 275);
FORCEPROP 1 LAST MATERIAL X7R
J 0
(1000 175);
DISPLAY 0.510638 (1000 175);
FORCEPROP 1 LAST VALUE 0.1UF
J 0
(1000 325);
DISPLAY 0.510638 (1000 325);
FORCEPROP 1 LAST TOLERANCE 10%
J 0
(1000 225);
DISPLAY 0.510638 (1000 225);
FORCEPROP 1 LAST PACK_TYPE 0402
J 0
(1000 75);
DISPLAY 0.510638 (1000 75);
FORCEPROP 1 LAST $LOCATION C2394
J 0
(1000 375);
DISPLAY 0.978723 (1000 375);
FORCEPROP 1 LASTPIN (950 375) $PN 1
J 0
(960 355);
DISPLAY 0.787234 (960 355);
PAINT MONO (960 355);
FORCEPROP 1 LASTPIN (950 175) $PN 2
J 0
(960 155);
DISPLAY 0.787234 (960 155);
PAINT MONO (960 155);
FORCEPROP 2 LAST CDS_LIB pure_quanta
J 0
(950 275);
DISPLAY INVISIBLE (950 275);
FORCEPROP 1 LAST PATH I93
J 0
(1000 425);
DISPLAY 0.978723 (1000 425);
PAINT WHITE (1000 425);
DISPLAY INVISIBLE (1000 425);
FORCEPROP 0 LAST CDS_LOCATION C2394
J 0
(1000 425);
DISPLAY 1.021277 (1000 425);
DISPLAY INVISIBLE (1000 425);
FORCEPROP 0 LAST $SEC 1
J 0
(1000 425);
DISPLAY 0.680851 (1000 425);
PAINT MONO (1000 425);
DISPLAY INVISIBLE (1000 425);
FORCEPROP 0 LAST CDS_SEC 1
J 0
(1000 425);
DISPLAY 1.021277 (1000 425);
DISPLAY INVISIBLE (1000 425);
FORCEADD UNIVERSAL_GND..1
(950 25);
FORCEPROP 3 LASTPIN (950 75) SIG_NAME GND\g
J 0
(960 85);
DISPLAY 0.659574 (960 85);
PAINT MONO (960 85);
DISPLAY INVISIBLE (960 85);
FORCEPROP 2 LAST CDS_LIB logical_power
J 0
(950 25);
DISPLAY INVISIBLE (950 25);
FORCEPROP 1 LAST PATH I94
J 0
(1025 25);
DISPLAY 0.872340 (1025 25);
PAINT AQUA (1025 25);
DISPLAY INVISIBLE (1025 25);
FORCEPROP 1 LAST HDL_POWER GND
J 1
(975 -50);
DISPLAY 0.872340 (975 -50);
PAINT GREEN (975 -50);
DISPLAY INVISIBLE (975 -50);
FORCEADD Q_CAP..1
(-1625 -1025);
FORCEPROP 1 LAST PART_NUMBER CH4104K1B00
J 0
(-1575 -1175);
DISPLAY 0.510638 (-1575 -1175);
DISPLAY INVISIBLE (-1575 -1175);
FORCEPROP 1 LAST VALUE 0.1UF
J 0
(-1575 -975);
DISPLAY 0.510638 (-1575 -975);
FORCEPROP 1 LAST VOLTAGE 25V
J 0
(-1575 -1025);
DISPLAY 0.510638 (-1575 -1025);
FORCEPROP 1 LAST PACK_TYPE 0402
J 0
(-1575 -1225);
DISPLAY 0.510638 (-1575 -1225);
FORCEPROP 1 LAST TOLERANCE 10%
J 0
(-1575 -1075);
DISPLAY 0.510638 (-1575 -1075);
FORCEPROP 1 LAST MATERIAL EMPTY
J 0
(-1575 -1125);
DISPLAY 0.510638 (-1575 -1125);
FORCEPROP 1 LAST $LOCATION C2392
J 0
(-1575 -925);
DISPLAY 0.978723 (-1575 -925);
FORCEPROP 1 LASTPIN (-1625 -925) $PN 1
J 0
(-1615 -945);
DISPLAY 0.787234 (-1615 -945);
PAINT MONO (-1615 -945);
FORCEPROP 1 LASTPIN (-1625 -1125) $PN 2
J 0
(-1615 -1145);
DISPLAY 0.787234 (-1615 -1145);
PAINT MONO (-1615 -1145);
FORCEPROP 2 LAST CDS_LIB pure_quanta
J 0
(-1625 -1025);
DISPLAY INVISIBLE (-1625 -1025);
FORCEPROP 1 LAST PATH I95
J 0
(-1575 -875);
DISPLAY 0.978723 (-1575 -875);
PAINT WHITE (-1575 -875);
DISPLAY INVISIBLE (-1575 -875);
FORCEPROP 0 LAST CDS_LOCATION C2392
J 0
(-1575 -875);
DISPLAY 1.021277 (-1575 -875);
DISPLAY INVISIBLE (-1575 -875);
FORCEPROP 0 LAST $SEC 1
J 0
(-1575 -875);
DISPLAY 0.680851 (-1575 -875);
PAINT MONO (-1575 -875);
DISPLAY INVISIBLE (-1575 -875);
FORCEPROP 0 LAST CDS_SEC 1
J 0
(-1575 -875);
DISPLAY 1.021277 (-1575 -875);
DISPLAY INVISIBLE (-1575 -875);
FORCEADD UNIVERSAL_GND..1
(-1625 -1250);
FORCEPROP 3 LASTPIN (-1625 -1200) SIG_NAME GND\g
J 0
(-1615 -1190);
DISPLAY 0.659574 (-1615 -1190);
PAINT MONO (-1615 -1190);
DISPLAY INVISIBLE (-1615 -1190);
FORCEPROP 2 LAST CDS_LIB logical_power
J 0
(-1625 -1250);
DISPLAY INVISIBLE (-1625 -1250);
FORCEPROP 1 LAST PATH I96
J 0
(-1550 -1250);
DISPLAY 0.872340 (-1550 -1250);
PAINT AQUA (-1550 -1250);
DISPLAY INVISIBLE (-1550 -1250);
FORCEPROP 1 LAST HDL_POWER GND
J 1
(-1600 -1325);
DISPLAY 0.872340 (-1600 -1325);
PAINT GREEN (-1600 -1325);
DISPLAY INVISIBLE (-1600 -1325);
FORCEADD Q_RES..2
(-1300 -675);
FORCEPROP 1 LAST PART_NUMBER CS21002FB06
J 0
(-1260 -800);
DISPLAY 0.723404 (-1260 -800);
PAINT WHITE (-1260 -800);
DISPLAY INVISIBLE (-1260 -800);
FORCEPROP 1 LAST TOLERANCE 1%
J 0
(-1255 -650);
DISPLAY 0.723404 (-1255 -650);
PAINT SKYBLUE (-1255 -650);
FORCEPROP 1 LAST WATTAGE 1/16W
J 0
(-1260 -700);
DISPLAY 0.723404 (-1260 -700);
PAINT SKYBLUE (-1260 -700);
FORCEPROP 1 LAST VALUE 1K
J 0
(-1255 -600);
DISPLAY 0.723404 (-1255 -600);
PAINT SKYBLUE (-1255 -600);
FORCEPROP 1 LAST MATERIAL EMPTY
J 0
(-1260 -750);
DISPLAY 0.723404 (-1260 -750);
PAINT SKYBLUE (-1260 -750);
FORCEPROP 1 LAST PACK_TYPE 0402LF
J 0
(-1260 -850);
DISPLAY 0.723404 (-1260 -850);
PAINT SKYBLUE (-1260 -850);
FORCEPROP 1 LAST LOCATION R4804
J 0
(-1255 -550);
DISPLAY 0.723404 (-1255 -550);
PAINT AQUA (-1255 -550);
FORCEPROP 1 LASTPIN (-1300 -575) $PN 1
J 0
(-1295 -613);
DISPLAY 0.787234 (-1295 -613);
PAINT MONO (-1295 -613);
FORCEPROP 1 LASTPIN (-1300 -775) $PN 2
J 0
(-1295 -765);
DISPLAY 0.787234 (-1295 -765);
PAINT MONO (-1295 -765);
FORCEPROP 1 LAST PATH I97
J 0
(-1250 -500);
DISPLAY 0.978723 (-1250 -500);
PAINT WHITE (-1250 -500);
DISPLAY INVISIBLE (-1250 -500);
FORCEPROP 2 LAST CDS_LIB pure_quanta
J 0
(-1300 -675);
DISPLAY INVISIBLE (-1300 -675);
FORCEPROP 0 LAST $SEC 1
J 0
(-1250 -500);
DISPLAY 0.680851 (-1250 -500);
PAINT MONO (-1250 -500);
DISPLAY INVISIBLE (-1250 -500);
FORCEPROP 0 LAST CDS_SEC 1
J 0
(-1250 -500);
DISPLAY 1.021277 (-1250 -500);
DISPLAY INVISIBLE (-1250 -500);
FORCEADD Q_RES..2
(1275 675);
FORCEPROP 1 LAST PART_NUMBER CS21002FB06
J 0
(1315 550);
DISPLAY 0.723404 (1315 550);
PAINT WHITE (1315 550);
DISPLAY INVISIBLE (1315 550);
FORCEPROP 1 LAST TOLERANCE 1%
J 0
(1320 700);
DISPLAY 0.723404 (1320 700);
PAINT SKYBLUE (1320 700);
FORCEPROP 1 LAST VALUE 1K
J 0
(1320 750);
DISPLAY 0.723404 (1320 750);
PAINT SKYBLUE (1320 750);
FORCEPROP 1 LAST MATERIAL CHIP
J 0
(1315 600);
DISPLAY 0.723404 (1315 600);
PAINT SKYBLUE (1315 600);
FORCEPROP 1 LAST PACK_TYPE 0402LF
J 0
(1315 500);
DISPLAY 0.723404 (1315 500);
PAINT SKYBLUE (1315 500);
FORCEPROP 1 LAST WATTAGE 1/16W
J 0
(1315 650);
DISPLAY 0.723404 (1315 650);
PAINT SKYBLUE (1315 650);
FORCEPROP 1 LAST LOCATION R4806
J 0
(1320 800);
DISPLAY 0.723404 (1320 800);
PAINT AQUA (1320 800);
FORCEPROP 1 LASTPIN (1275 775) $PN 1
J 0
(1280 737);
DISPLAY 0.787234 (1280 737);
PAINT MONO (1280 737);
FORCEPROP 1 LASTPIN (1275 575) $PN 2
J 0
(1280 585);
DISPLAY 0.787234 (1280 585);
PAINT MONO (1280 585);
FORCEPROP 1 LAST PATH I98
J 0
(1325 850);
DISPLAY 0.978723 (1325 850);
PAINT WHITE (1325 850);
DISPLAY INVISIBLE (1325 850);
FORCEPROP 2 LAST CDS_LIB pure_quanta
J 0
(1275 675);
DISPLAY INVISIBLE (1275 675);
FORCEPROP 0 LAST $SEC 1
J 0
(1325 850);
DISPLAY 0.680851 (1325 850);
PAINT MONO (1325 850);
DISPLAY INVISIBLE (1325 850);
FORCEPROP 0 LAST CDS_SEC 1
J 0
(1325 850);
DISPLAY 1.021277 (1325 850);
DISPLAY INVISIBLE (1325 850);
FORCEADD Q_RES..2
(650 4450);
FORCEPROP 1 LAST PART_NUMBER CS21002FB06
J 0
(690 4325);
DISPLAY 0.723404 (690 4325);
PAINT WHITE (690 4325);
DISPLAY INVISIBLE (690 4325);
FORCEPROP 1 LAST PACK_TYPE 0402LF
J 0
(690 4275);
DISPLAY 0.723404 (690 4275);
PAINT SKYBLUE (690 4275);
FORCEPROP 1 LAST VALUE 1K
J 0
(695 4525);
DISPLAY 0.723404 (695 4525);
PAINT SKYBLUE (695 4525);
FORCEPROP 1 LAST TOLERANCE 1%
J 0
(695 4475);
DISPLAY 0.723404 (695 4475);
PAINT SKYBLUE (695 4475);
FORCEPROP 1 LAST WATTAGE 1/16W
J 0
(690 4425);
DISPLAY 0.723404 (690 4425);
PAINT SKYBLUE (690 4425);
FORCEPROP 1 LAST MATERIAL EMPTY
J 0
(690 4375);
DISPLAY 0.723404 (690 4375);
PAINT SKYBLUE (690 4375);
FORCEPROP 1 LAST LOCATION R4805
J 0
(695 4575);
DISPLAY 0.723404 (695 4575);
PAINT AQUA (695 4575);
FORCEPROP 1 LASTPIN (650 4550) $PN 1
J 0
(655 4512);
DISPLAY 0.787234 (655 4512);
PAINT MONO (655 4512);
FORCEPROP 1 LASTPIN (650 4350) $PN 2
J 0
(655 4360);
DISPLAY 0.787234 (655 4360);
PAINT MONO (655 4360);
FORCEPROP 1 LAST PATH I99
J 0
(700 4625);
DISPLAY 0.978723 (700 4625);
PAINT WHITE (700 4625);
DISPLAY INVISIBLE (700 4625);
FORCEPROP 2 LAST CDS_LIB pure_quanta
J 0
(650 4450);
DISPLAY INVISIBLE (650 4450);
FORCEPROP 0 LAST $SEC 1
J 0
(700 4625);
DISPLAY 0.680851 (700 4625);
PAINT MONO (700 4625);
DISPLAY INVISIBLE (700 4625);
FORCEPROP 0 LAST CDS_SEC 1
J 0
(700 4625);
DISPLAY 1.021277 (700 4625);
DISPLAY INVISIBLE (700 4625);
FORCEADD DNS..1
(-1250 1925);
PAINT RED (-1250 1925);
FORCEPROP 2 LAST CDS_LIB mstr_misc
J 0
(-1250 1925);
DISPLAY INVISIBLE (-1250 1925);
FORCEPROP 1 LAST COMMENT_BODY TRUE
R 1
J 0
(-1175 1700);
DISPLAY 0.872340 (-1175 1700);
PAINT GREEN (-1175 1700);
DISPLAY INVISIBLE (-1175 1700);
FORCEADD DNS..1
(125 1325);
PAINT RED (125 1325);
FORCEPROP 2 LAST CDS_LIB mstr_misc
J 0
(125 1325);
DISPLAY INVISIBLE (125 1325);
FORCEPROP 1 LAST COMMENT_BODY TRUE
R 1
J 0
(200 1100);
DISPLAY 0.872340 (200 1100);
PAINT GREEN (200 1100);
DISPLAY INVISIBLE (200 1100);
FORCEADD QUANTA_TITLE_BLOCK_C..1
(5950 -1925);
FORCEPROP 0 LAST CDS_CON_LAST_MODIFIED Fri Aug 25 14:05:25 2023
J 0
(4065 -1910);
PAINT MONO (4065 -1910);
DISPLAY INVISIBLE (4065 -1910);
FORCEPROP 1 LAST CUSTOM_TXT_CDS <CON_LAST_MODIFIED>
J 0
(4065 -1910);
DISPLAY 0.978723 (4065 -1910);
FORCEPROP 2 LAST CUSTOM_TXT_CDS <XR_PAGE_TITLE>
J 0
(-1940 3325);
DISPLAY 0.638298 (-1940 3325);
PAINT PINK (-1940 3325);
DISPLAY INVISIBLE (-1940 3325);
FORCEPROP 1 LAST CUSTOM_TXT_CDS <NAME_2>
J 0
(2775 -1875);
FORCEPROP 1 LAST CUSTOM_TXT_CDS <NAME_1>
J 0
(2775 -1750);
FORCEPROP 1 LAST CUSTOM_TXT_CDS <Q_NUMBER>
J 0
(4547 -1822);
DISPLAY 1.212766 (4547 -1822);
FORCEPROP 1 LAST CUSTOM_TXT_CDS <Q_PROJ>
J 0
(3568 -1823);
DISPLAY 1.212766 (3568 -1823);
FORCEPROP 1 LAST CUSTOM_TXT_CDS <Q_REV>
J 0
(5766 -1822);
DISPLAY 1.212766 (5766 -1822);
FORCEPROP 1 LAST CUSTOM_TXT_CDS <CON_PAGE_NUM> OF <CON_TOTAL_PAGES>
J 0
(5504 -1907);
DISPLAY 0.978723 (5504 -1907);
FORCEPROP 1 LAST Q_TITLE HSC MODULE(3/4)
J 0
(-3416 -1899);
DISPLAY 2.446809 (-3416 -1899);
PAINT GREEN (-3416 -1899);
FORCEPROP 1 LAST Q_DEPT 
J 1
(2187 -1876);
DISPLAY 1.957447 (2187 -1876);
PAINT GREEN (2187 -1876);
FORCEPROP 2 LAST CDS_XR_PAGE_TITLE CR-306 : @S9S_MB_2U_LIB.S9S_MB_2U(SCH_1):PAGE306
J 0
(-1940 3325);
DISPLAY 0.638298 (-1940 3325);
PAINT PINK (-1940 3325);
DISPLAY INVISIBLE (-1940 3325);
FORCEPROP 1 LAST COMMENT_BODY TRUE
J 0
(5962 -1938);
DISPLAY 0.978723 (5962 -1938);
PAINT GREEN (5962 -1938);
DISPLAY INVISIBLE (5962 -1938);
FORCEPROP 2 LAST PAGE_BORDER TRUE
J 0
(-1940 3325);
DISPLAY 0.638298 (-1940 3325);
PAINT PINK (-1940 3325);
DISPLAY INVISIBLE (-1940 3325);
FORCEPROP 1 LAST CDS_LMAN_SYM_OUTLINE -9475,6775,100,-125
J 0
(5950 -1925);
DISPLAY 0.468085 (5950 -1925);
PAINT GREEN (5950 -1925);
DISPLAY INVISIBLE (5950 -1925);
FORCEPROP 2 LAST CDS_LIB pure_quanta
J 0
(5950 -1925);
PAINT MONO (5950 -1925);
DISPLAY INVISIBLE (5950 -1925);
FORCEADD DNS..1
(-1625 -1075);
PAINT RED (-1625 -1075);
FORCEPROP 1 LAST COMMENT_BODY TRUE
R 1
J 0
(-1550 -1300);
DISPLAY 0.872340 (-1550 -1300);
PAINT GREEN (-1550 -1300);
DISPLAY INVISIBLE (-1550 -1300);
FORCEPROP 2 LAST CDS_LIB mstr_misc
J 0
(-1625 -1075);
DISPLAY INVISIBLE (-1625 -1075);
FORCEADD DNS..1
(-1300 -725);
PAINT RED (-1300 -725);
FORCEPROP 2 LAST CDS_LIB mstr_misc
J 0
(-1300 -725);
DISPLAY INVISIBLE (-1300 -725);
FORCEPROP 1 LAST COMMENT_BODY TRUE
R 1
J 0
(-1225 -950);
DISPLAY 0.872340 (-1225 -950);
PAINT GREEN (-1225 -950);
DISPLAY INVISIBLE (-1225 -950);
FORCEADD DNS..1
(875 1725);
PAINT RED (875 1725);
FORCEPROP 2 LAST CDS_LIB mstr_misc
J 0
(875 1725);
DISPLAY INVISIBLE (875 1725);
FORCEPROP 1 LAST COMMENT_BODY TRUE
R 1
J 0
(950 1500);
DISPLAY 0.872340 (950 1500);
PAINT GREEN (950 1500);
DISPLAY INVISIBLE (950 1500);
FORCEADD DNS..1
(2300 1750);
PAINT RED (2300 1750);
FORCEPROP 2 LAST CDS_LIB mstr_misc
J 0
(2300 1750);
DISPLAY INVISIBLE (2300 1750);
FORCEPROP 1 LAST COMMENT_BODY TRUE
R 1
J 0
(2375 1525);
DISPLAY 0.872340 (2375 1525);
PAINT GREEN (2375 1525);
DISPLAY INVISIBLE (2375 1525);
FORCEADD DNS..1
(3100 2000);
PAINT RED (3100 2000);
FORCEPROP 2 LAST CDS_LIB mstr_misc
J 0
(3100 2000);
DISPLAY INVISIBLE (3100 2000);
FORCEPROP 1 LAST COMMENT_BODY TRUE
R 1
J 0
(3175 1775);
DISPLAY 0.872340 (3175 1775);
PAINT GREEN (3175 1775);
DISPLAY INVISIBLE (3175 1775);
FORCEADD DNS..1
(1150 2350);
PAINT RED (1150 2350);
FORCEPROP 2 LAST CDS_LIB mstr_misc
J 0
(1150 2350);
DISPLAY INVISIBLE (1150 2350);
FORCEPROP 1 LAST COMMENT_BODY TRUE
R 1
J 0
(1225 2125);
DISPLAY 0.872340 (1225 2125);
PAINT GREEN (1225 2125);
DISPLAY INVISIBLE (1225 2125);
FORCEADD DNS..1
(550 1325);
PAINT RED (550 1325);
FORCEPROP 2 LAST CDS_LIB mstr_misc
J 0
(550 1325);
DISPLAY INVISIBLE (550 1325);
FORCEPROP 1 LAST COMMENT_BODY TRUE
R 1
J 0
(625 1100);
DISPLAY 0.872340 (625 1100);
PAINT GREEN (625 1100);
DISPLAY INVISIBLE (625 1100);
FORCEADD DNS..1
(-275 2000);
PAINT RED (-275 2000);
FORCEPROP 1 LAST COMMENT_BODY TRUE
R 1
J 0
(-200 1775);
DISPLAY 0.872340 (-200 1775);
PAINT GREEN (-200 1775);
DISPLAY INVISIBLE (-200 1775);
FORCEPROP 2 LAST CDS_LIB mstr_misc
J 0
(-275 2000);
DISPLAY INVISIBLE (-275 2000);
FORCEADD DNS..1
(-275 1400);
PAINT RED (-275 1400);
FORCEPROP 1 LAST COMMENT_BODY TRUE
R 1
J 0
(-200 1175);
DISPLAY 0.872340 (-200 1175);
PAINT GREEN (-200 1175);
DISPLAY INVISIBLE (-200 1175);
FORCEPROP 2 LAST CDS_LIB mstr_misc
J 0
(-275 1400);
DISPLAY INVISIBLE (-275 1400);
FORCEADD DNS..1
(-875 1100);
PAINT RED (-875 1100);
FORCEPROP 2 LAST CDS_LIB mstr_misc
J 0
(-875 1100);
DISPLAY INVISIBLE (-875 1100);
FORCEPROP 1 LAST COMMENT_BODY TRUE
R 1
J 0
(-800 875);
DISPLAY 0.872340 (-800 875);
PAINT GREEN (-800 875);
DISPLAY INVISIBLE (-800 875);
FORCEADD DNS..1
(1050 3775);
PAINT RED (1050 3775);
FORCEPROP 1 LAST COMMENT_BODY TRUE
R 1
J 0
(1125 3550);
DISPLAY 0.872340 (1125 3550);
PAINT GREEN (1125 3550);
DISPLAY INVISIBLE (1125 3550);
FORCEPROP 2 LAST CDS_LIB mstr_misc
J 0
(1050 3775);
DISPLAY INVISIBLE (1050 3775);
FORCEADD DNS..1
(2800 4050);
PAINT RED (2800 4050);
FORCEPROP 1 LAST COMMENT_BODY TRUE
R 1
J 0
(2875 3825);
DISPLAY 0.872340 (2875 3825);
PAINT GREEN (2875 3825);
DISPLAY INVISIBLE (2875 3825);
FORCEPROP 2 LAST CDS_LIB mstr_misc
J 0
(2800 4050);
DISPLAY INVISIBLE (2800 4050);
FORCEADD DNS..1
(3575 3950);
PAINT RED (3575 3950);
FORCEPROP 1 LAST COMMENT_BODY TRUE
R 1
J 0
(3650 3725);
DISPLAY 0.872340 (3650 3725);
PAINT GREEN (3650 3725);
DISPLAY INVISIBLE (3650 3725);
FORCEPROP 2 LAST CDS_LIB mstr_misc
J 0
(3575 3950);
DISPLAY INVISIBLE (3575 3950);
FORCEADD DNS..1
(1950 4100);
PAINT RED (1950 4100);
FORCEPROP 1 LAST COMMENT_BODY TRUE
R 1
J 0
(2025 3875);
DISPLAY 0.872340 (2025 3875);
PAINT GREEN (2025 3875);
DISPLAY INVISIBLE (2025 3875);
FORCEPROP 2 LAST CDS_LIB mstr_misc
J 0
(1950 4100);
DISPLAY INVISIBLE (1950 4100);
FORCEADD DNS..1
(1675 4100);
PAINT RED (1675 4100);
FORCEPROP 1 LAST COMMENT_BODY TRUE
R 1
J 0
(1750 3875);
DISPLAY 0.872340 (1750 3875);
PAINT GREEN (1750 3875);
DISPLAY INVISIBLE (1750 3875);
FORCEPROP 2 LAST CDS_LIB mstr_misc
J 0
(1675 4100);
DISPLAY INVISIBLE (1675 4100);
FORCEADD DNS..1
(2000 3350);
PAINT RED (2000 3350);
FORCEPROP 2 LAST CDS_LIB mstr_misc
J 0
(2000 3350);
DISPLAY INVISIBLE (2000 3350);
FORCEPROP 1 LAST COMMENT_BODY TRUE
R 1
J 0
(2075 3125);
DISPLAY 0.872340 (2075 3125);
PAINT GREEN (2075 3125);
DISPLAY INVISIBLE (2075 3125);
FORCEADD DNS..1
(1025 3050);
PAINT RED (1025 3050);
FORCEPROP 2 LAST CDS_LIB mstr_misc
J 0
(1025 3050);
DISPLAY INVISIBLE (1025 3050);
FORCEPROP 1 LAST COMMENT_BODY TRUE
R 1
J 0
(1100 2825);
DISPLAY 0.872340 (1100 2825);
PAINT GREEN (1100 2825);
DISPLAY INVISIBLE (1100 2825);
FORCEADD DNS..1
(-525 3425);
PAINT RED (-525 3425);
FORCEPROP 2 LAST CDS_LIB mstr_misc
J 0
(-525 3425);
DISPLAY INVISIBLE (-525 3425);
FORCEPROP 1 LAST COMMENT_BODY TRUE
R 1
J 0
(-450 3200);
DISPLAY 0.872340 (-450 3200);
PAINT GREEN (-450 3200);
DISPLAY INVISIBLE (-450 3200);
FORCEADD DNS..1
(-575 4025);
PAINT RED (-575 4025);
FORCEPROP 1 LAST COMMENT_BODY TRUE
R 1
J 0
(-500 3800);
DISPLAY 0.872340 (-500 3800);
PAINT GREEN (-500 3800);
DISPLAY INVISIBLE (-500 3800);
FORCEPROP 2 LAST CDS_LIB mstr_misc
J 0
(-575 4025);
DISPLAY INVISIBLE (-575 4025);
FORCEADD DNS..1
(-1100 4025);
PAINT RED (-1100 4025);
FORCEPROP 1 LAST COMMENT_BODY TRUE
R 1
J 0
(-1025 3800);
DISPLAY 0.872340 (-1025 3800);
PAINT GREEN (-1025 3800);
DISPLAY INVISIBLE (-1025 3800);
FORCEPROP 2 LAST CDS_LIB mstr_misc
J 0
(-1100 4025);
DISPLAY INVISIBLE (-1100 4025);
FORCEADD DNS..1
(-1100 3425);
PAINT RED (-1100 3425);
FORCEPROP 1 LAST COMMENT_BODY TRUE
R 1
J 0
(-1025 3200);
DISPLAY 0.872340 (-1025 3200);
PAINT GREEN (-1025 3200);
DISPLAY INVISIBLE (-1025 3200);
FORCEPROP 2 LAST CDS_LIB mstr_misc
J 0
(-1100 3425);
DISPLAY INVISIBLE (-1100 3425);
FORCEADD DNS..1
(-700 -1450);
PAINT RED (-700 -1450);
FORCEPROP 2 LAST CDS_LIB mstr_misc
J 0
(-700 -1450);
DISPLAY INVISIBLE (-700 -1450);
FORCEPROP 1 LAST COMMENT_BODY TRUE
R 1
J 0
(-625 -1675);
DISPLAY 0.872340 (-625 -1675);
PAINT GREEN (-625 -1675);
DISPLAY INVISIBLE (-625 -1675);
FORCEADD DNS..1
(925 -1400);
PAINT RED (925 -1400);
FORCEPROP 1 LAST COMMENT_BODY TRUE
R 1
J 0
(1000 -1625);
DISPLAY 0.872340 (1000 -1625);
PAINT GREEN (1000 -1625);
DISPLAY INVISIBLE (1000 -1625);
FORCEPROP 2 LAST CDS_LIB mstr_misc
J 0
(925 -1400);
DISPLAY 0.808511 (925 -1400);
DISPLAY INVISIBLE (925 -1400);
FORCEADD DNS..1
(-2575 -925);
PAINT RED (-2575 -925);
FORCEPROP 1 LAST COMMENT_BODY TRUE
R 1
J 0
(-2500 -1150);
DISPLAY 0.872340 (-2500 -1150);
PAINT GREEN (-2500 -1150);
DISPLAY INVISIBLE (-2500 -1150);
FORCEPROP 2 LAST CDS_LIB mstr_misc
J 0
(-2575 -925);
DISPLAY INVISIBLE (-2575 -925);
FORCEADD DNS..1
(-2575 -1300);
PAINT RED (-2575 -1300);
FORCEPROP 2 LAST CDS_LIB mstr_misc
J 0
(-2575 -1300);
DISPLAY INVISIBLE (-2575 -1300);
FORCEPROP 1 LAST COMMENT_BODY TRUE
R 1
J 0
(-2500 -1525);
DISPLAY 0.872340 (-2500 -1525);
PAINT GREEN (-2500 -1525);
DISPLAY INVISIBLE (-2500 -1525);
FORCEADD DNS..1
(25 4100);
PAINT RED (25 4100);
FORCEPROP 1 LAST COMMENT_BODY TRUE
R 1
J 0
(100 3875);
DISPLAY 0.872340 (100 3875);
PAINT GREEN (100 3875);
DISPLAY INVISIBLE (100 3875);
FORCEPROP 2 LAST CDS_LIB mstr_misc
J 0
(25 4100);
DISPLAY INVISIBLE (25 4100);
FORCEADD DNS..1
(650 4425);
PAINT RED (650 4425);
FORCEPROP 2 LAST CDS_LIB mstr_misc
J 0
(650 4425);
DISPLAY INVISIBLE (650 4425);
FORCEPROP 1 LAST COMMENT_BODY TRUE
R 1
J 0
(725 4200);
DISPLAY 0.872340 (725 4200);
PAINT GREEN (725 4200);
DISPLAY INVISIBLE (725 4200);
FORCEADD DNS..1
(400 4075);
PAINT RED (400 4075);
FORCEPROP 2 LAST CDS_LIB mstr_misc
J 0
(400 4075);
DISPLAY INVISIBLE (400 4075);
FORCEPROP 1 LAST COMMENT_BODY TRUE
R 1
J 0
(475 3850);
DISPLAY 0.872340 (475 3850);
PAINT GREEN (475 3850);
DISPLAY INVISIBLE (475 3850);
FORCEADD DNS..1
(-2025 -1050);
PAINT RED (-2025 -1050);
FORCEPROP 1 LAST COMMENT_BODY TRUE
R 1
J 0
(-1950 -1275);
DISPLAY 0.872340 (-1950 -1275);
PAINT GREEN (-1950 -1275);
DISPLAY INVISIBLE (-1950 -1275);
FORCEPROP 2 LAST CDS_LIB mstr_misc
J 0
(-2025 -1050);
DISPLAY INVISIBLE (-2025 -1050);
WIRE 16 -1 (4050 550)(4050 675);
WIRE 16 -1 (900 2525)(900 2550);
WIRE 16 -1 (900 2525)(1150 2525);
WIRE 16 -1 (900 2000)(900 2525);
WIRE 16 -1 (75 575)(75 375);
WIRE 16 -1 (-1300 -475)(-1300 -575);
WIRE 16 -1 (2400 475)(2400 575);
WIRE 16 -1 (2400 475)(2675 475);
WIRE 16 -1 (2400 350)(2400 475);
WIRE 16 -1 (3100 2300)(3100 2125);
WIRE 16 -1 (-1275 2250)(-1275 2075);
WIRE 16 -1 (1675 4350)(1675 4450);
WIRE 16 -1 (1675 4350)(1950 4350);
WIRE 16 -1 (1675 4225)(1675 4350);
WIRE 16 -1 (650 4600)(650 4550);
WIRE 16 -1 (-525 575)(-525 375);
WIRE 16 -1 (-2575 -775)(-2575 -675);
WIRE 16 -1 (1150 2225)(1150 2275);
WIRE 16 -1 (900 1375)(900 1500);
WIRE 16 -1 (125 1125)(125 1250);
WIRE 16 -1 (-275 1125)(-275 1250);
WIRE 16 -1 (-1250 1000)(-1250 875);
WIRE 16 -1 (-1225 1000)(-1250 1000);
WIRE 16 -1 (2850 3825)(2850 3900);
WIRE 16 -1 (1975 3225)(1975 3300);
WIRE 16 -1 (1525 3525)(1525 3600);
WIRE 16 -1 (-550 3225)(-550 3150);
WIRE 16 -1 (-550 3225)(-1100 3225);
WIRE 16 -1 (-550 3350)(-550 3225);
WIRE 16 -1 (4050 -450)(4050 -325);
WIRE 16 -1 (2300 -400)(2300 -275);
WIRE 16 -1 (75 -575)(75 -725);
WIRE 16 -1 (-525 -575)(-525 -725);
WIRE 16 -1 (-275 -1600)(-275 -1525);
WIRE 16 -1 (-2575 -1375)(-2575 -1475);
WIRE 16 -1 (0 3875)(0 3850);
WIRE 16 -1 (400 3875)(0 3875);
WIRE 16 -1 (0 4000)(0 3875);
WIRE 16 -1 (550 175)(550 75);
WIRE 16 -1 (950 175)(950 75);
WIRE 16 -1 (-2025 -1125)(-2025 -1225);
WIRE 16 -1 (-1625 -1125)(-1625 -1200);
WIRE 16 -1 (1275 850)(1275 775);
WIRE 16 -1 (550 1125)(550 1250);
WIRE 16 -1 (-1275 1300)(-1225 1300);
WIRE 16 -1 (125 1450)(125 1700);
WIRE 16 -1 (125 1700)(650 1700);
WIRE 16 -1 (-1275 1875)(-1275 1700);
WIRE 16 -1 (-1275 1300)(-1275 1700);
WIRE 16 -1 (-1275 1700)(125 1700);
FORCEPROP 2 LAST SIG_NAME OC_P2V5_COMP
J 0
(-135 1710);
DISPLAY 0.723404 (-135 1710);
WIRE 16 -1 (550 375)(550 475);
WIRE 16 -1 (950 375)(950 475);
WIRE 16 -1 (550 475)(950 475);
FORCEPROP 2 LAST SIG_NAME U206_VDD
J 0
(690 485);
DISPLAY 0.638298 (690 485);
PAINT WHITE (690 485);
WIRE 16 -1 (1275 575)(1275 475);
WIRE 16 -1 (950 475)(1275 475);
WIRE 16 -1 (1275 -75)(1475 -75);
WIRE 16 -1 (1275 -75)(1275 475);
WIRE 16 -1 (-675 2225)(-275 2225);
FORCEPROP 2 LAST SIG_NAME HSC_CSOUT
J 0
(-654 2225);
DISPLAY 0.723404 (-654 2225);
WIRE 16 -1 (-275 2225)(-275 2125);
WIRE 16 -1 (600 2075)(1250 2075);
WIRE 16 -1 (600 1800)(650 1800);
WIRE 16 -1 (600 1800)(600 2075);
WIRE 16 -1 (550 1450)(550 1800);
WIRE 16 -1 (550 1800)(600 1800);
WIRE 16 -1 (-275 1800)(-275 1450);
WIRE 16 -1 (-275 1800)(-275 1925);
WIRE 16 -1 (-275 1800)(550 1800);
FORCEPROP 2 LAST SIG_NAME HSC_OC_VOL
J 0
(-254 1800);
DISPLAY 0.723404 (-254 1800);
WIRE 16 -1 (1150 1750)(1975 1750);
FORCEPROP 2 LAST SIG_NAME HSC_D_OC_R2
J 0
(1215 1760);
DISPLAY 0.723404 (1215 1760);
WIRE 16 -1 (2175 1750)(1975 1750);
WIRE 16 -1 (1975 2075)(1975 1750);
WIRE 16 -1 (1450 2075)(1975 2075);
WIRE 16 2175 (-650 -675)(275 -675);
WIRE 16 2175 (275 -675)(275 -825);
WIRE 16 2175 (-650 -675)(-650 -825);
WIRE 16 2175 (-650 -825)(275 -825);
WIRE 16 -1 (1475 -225)(75 -225);
FORCEPROP 2 LAST SIG_NAME A_P12V_STBY_FP_TRIGGER
J 0
(215 -215);
DISPLAY 0.723404 (215 -215);
WIRE 16 -1 (75 175)(75 -225);
WIRE 16 -1 (75 -375)(75 -225);
WIRE 16 -1 (-525 -125)(-525 175);
WIRE 16 -1 (1475 -125)(-525 -125);
FORCEPROP 2 LAST SIG_NAME A_P12V_STBY_ADR_TRIGGER
J 0
(215 -115);
DISPLAY 0.723404 (215 -115);
WIRE 16 -1 (-525 -375)(-525 -125);
WIRE 16 -1 (-1300 -1325)(-1100 -1325);
WIRE 16 -1 (-1300 -1325)(-1300 -825);
WIRE 16 -1 (-1300 -775)(-1300 -825);
WIRE 16 -1 (-1625 -925)(-1625 -825);
WIRE 16 -1 (-1625 -825)(-1300 -825);
WIRE 16 -1 (-2025 -825)(-1625 -825);
FORCEPROP 2 LAST SIG_NAME U205_VDD
J 0
(-1835 -815);
DISPLAY 0.638298 (-1835 -815);
PAINT WHITE (-1835 -815);
WIRE 16 -1 (-2025 -925)(-2025 -825);
WIRE 16 -1 (-1100 -1375)(-2200 -1375);
FORCEPROP 2 LAST SIG_NAME A_HSC_INAP
J 0
(-1860 -1365);
DISPLAY 0.723404 (-1860 -1365);
WIRE 16 -1 (-2200 -1375)(-2200 -1075);
WIRE 16 -1 (-2575 -1075)(-2575 -1175);
WIRE 16 -1 (-2200 -1075)(-2575 -1075);
WIRE 16 -1 (-2575 -975)(-2575 -1075);
WIRE 16 -1 (-1100 -1475)(-1975 -1475);
FORCEPROP 2 LAST SIG_NAME NC_U205_INB-
J 0
(-1635 -1465);
DISPLAY 0.723404 (-1635 -1465);
WIRE 16 -1 (2675 -125)(2225 -125);
WIRE 16 -1 (3525 -125)(2675 -125);
FORCEPROP 2 LAST SIG_NAME FM_UV_ADR_TRIGGER_N
J 0
(2765 -115);
DISPLAY 0.723404 (2765 -115);
WIRE 16 -1 (2675 -125)(2675 150);
WIRE 16 -1 (3900 -225)(2400 -225);
FORCEPROP 2 LAST SIG_NAME A_P12V_STBY_FPH_GATE
J 0
(2740 -215);
DISPLAY 0.723404 (2740 -215);
WIRE 16 -1 (2400 150)(2400 -225);
WIRE 16 -1 (2225 -225)(2400 -225);
WIRE 16 -1 (4050 200)(4050 350);
WIRE 16 -1 (4050 200)(5250 200);
FORCEPROP 2 LAST SIG_NAME IRQ_UV_DETECT_N
J 0
(4490 210);
DISPLAY 0.723404 (4490 210);
WIRE 16 -1 (4050 -25)(4050 200);
WIRE 16 -1 (2675 475)(2675 350);
WIRE 16 -1 (2300 -275)(2225 -275);
WIRE 16 -1 (-1425 3050)(900 3050);
WIRE 16 -1 (-1425 4325)(-1425 3050);
WIRE 16 -1 (-1425 4325)(-1575 4325);
FORCEPROP 2 LAST SIG_NAME HSC_CSOUT
J 0
(-1510 4335);
DISPLAY 0.808511 (-1510 4335);
WIRE 16 -1 (-1100 4325)(-1425 4325);
WIRE 16 -1 (-1100 4150)(-1100 4325);
WIRE 16 -1 (-1100 4325)(-550 4325);
WIRE 16 -1 (-550 4325)(-550 4150);
WIRE 16 -1 (1150 2525)(1150 2475);
WIRE 16 -1 (-550 3650)(-550 3550);
WIRE 16 -1 (-550 3950)(-550 3650);
WIRE 16 -1 (-550 3650)(700 3650);
FORCEPROP 2 LAST SIG_NAME A_HSC_HIGH
J 0
(-485 3660);
DISPLAY 0.808511 (-485 3660);
WIRE 16 -1 (-1100 3750)(-1100 3550);
WIRE 16 -1 (-1100 3950)(-1100 3750);
WIRE 16 -1 (700 3750)(-1100 3750);
FORCEPROP 2 LAST SIG_NAME A_HSC_LOW
J 0
(-485 3760);
DISPLAY 0.808511 (-485 3760);
WIRE 16 2175 (-2700 -1700)(-2400 -1700);
WIRE 16 2175 (-2400 -1450)(-2400 -1700);
WIRE 16 2175 (-2700 -1450)(-2700 -1700);
WIRE 16 2175 (-2700 -1450)(-2400 -1450);
WIRE 16 -1 (825 -1375)(-350 -1375);
FORCEPROP 2 LAST SIG_NAME PWRGD_DSW_PWROK_R4
J 0
(-135 -1365);
DISPLAY 0.723404 (-135 -1365);
WIRE 16 -1 (400 4000)(400 3875);
WIRE 16 -1 (-1100 3350)(-1100 3225);
WIRE 16 -1 (650 3800)(700 3800);
WIRE 16 -1 (650 3800)(650 4325);
WIRE 16 -1 (650 4350)(650 4325);
WIRE 16 -1 (400 4200)(400 4325);
WIRE 16 -1 (400 4325)(650 4325);
WIRE 16 -1 (0 4325)(400 4325);
FORCEPROP 2 LAST SIG_NAME U369_VDD
J 0
(190 4335);
DISPLAY 0.638298 (190 4335);
PAINT WHITE (190 4335);
WIRE 16 -1 (0 4200)(0 4325);
WIRE 16 -1 (3575 4425)(3575 4075);
WIRE 16 -1 (3575 4425)(2850 4425);
FORCEPROP 2 LAST SIG_NAME A_HSC_LOW_DRAIN
J 0
(2965 4435);
DISPLAY 0.808511 (2965 4435);
WIRE 16 -1 (2850 4300)(2850 4425);
WIRE 16 -1 (2025 -1375)(1025 -1375);
FORCEPROP 2 LAST SIG_NAME PWRGD_DSW_PWROK
J 0
(1365 -1365);
DISPLAY 0.723404 (1365 -1365);
WIRE 16 -1 (3100 1750)(2375 1750);
FORCEPROP 2 LAST SIG_NAME A_HSC_LOW_GATE
J 0
(2565 1760);
DISPLAY 0.723404 (2565 1760);
WIRE 16 -1 (3100 1925)(3100 1750);
WIRE 16 -1 (3350 1750)(3100 1750);
WIRE 16 -1 (1450 3750)(1950 3750);
WIRE 16 -1 (1950 3750)(1950 4025);
WIRE 16 -1 (1975 3500)(1975 3750);
WIRE 16 -1 (1975 3750)(1950 3750);
WIRE 16 -1 (2575 3750)(1975 3750);
FORCEPROP 2 LAST SIG_NAME A_HSC_LOW_GATE
J 0
(2040 3760);
DISPLAY 0.808511 (2040 3760);
WIRE 16 -1 (2575 3750)(2575 4100);
WIRE 16 -1 (2575 4100)(2650 4100);
WIRE 16 -1 (2525 4100)(2575 4100);
WIRE 16 -1 (1450 3650)(1675 3650);
WIRE 16 -1 (1675 4025)(1675 3650);
WIRE 16 -1 (1675 3650)(3575 3650);
WIRE 16 -1 (3575 3650)(3575 3875);
WIRE 16 -1 (3825 3650)(3575 3650);
FORCEPROP 2 LAST SIG_NAME HSC_D_OC
J 0
(3765 3660);
DISPLAY 0.808511 (3765 3660);
WIRE 16 -1 (3825 3650)(4200 3650);
WIRE 16 -1 (3825 3050)(3825 3650);
WIRE 16 -1 (1100 3050)(3825 3050);
WIRE 16 -1 (525 -1475)(-350 -1475);
FORCEPROP 2 LAST SIG_NAME NC_U205_OUTB
J 0
(-135 -1465);
DISPLAY 0.723404 (-135 -1465);
WIRE 16 -1 (1525 3600)(1450 3600);
WIRE 16 -1 (1950 4350)(1950 4225);
WIRE 16 -1 (-275 -1525)(-350 -1525);
DOT 1 (2400 475);
DOT 1 (1275 475);
DOT 1 (550 1800);
DOT 1 (1950 3750);
DOT 1 (-1300 -825);
DOT 1 (1675 4350);
DOT 1 (-2575 -1075);
DOT 1 (-525 -125);
DOT 1 (2400 -225);
DOT 1 (2675 -125);
DOT 1 (4050 200);
DOT 1 (-1100 3750);
DOT 1 (-1425 4325);
DOT 1 (-1100 4325);
DOT 1 (-550 3650);
DOT 1 (1675 3650);
DOT 1 (1975 3750);
DOT 1 (2575 4100);
DOT 1 (3575 3650);
DOT 1 (3825 3650);
DOT 1 (-1275 1700);
DOT 1 (-275 1800);
DOT 1 (125 1700);
DOT 1 (600 1800);
DOT 1 (1975 1750);
DOT 1 (900 2525);
DOT 1 (3100 1750);
DOT 1 (0 3875);
DOT 1 (650 4325);
DOT 1 (950 475);
DOT 1 (75 -225);
DOT 1 (-1625 -825);
DOT 1 (400 4325);
DOT 1 (-550 3225);
FORCENOTE
OC DETECT ON MODULE
(75 2800) 0;
DISPLAY LEFT (75 2800);
DISPLAY 2.510638 (75 2800);
PAINT PINK (75 2800);
FORCENOTE
20220811 ADD CO-LAY DESIGN
(1300 1300) 0;
DISPLAY LEFT (1300 1300);
DISPLAY 2.510638 (1300 1300);
PAINT PINK (1300 1300);
FORCENOTE
PROCHOT
(900 3400) 0;
DISPLAY LEFT (900 3400);
DISPLAY 1.021277 (900 3400);
FORCENOTE
20210705 MODIFY FOR GT
(3275 4575) 0;
DISPLAY LEFT (3275 4575);
DISPLAY 2.510638 (3275 4575);
PAINT PINK (3275 4575);
QUIT
